FILE_TYPE = MACRO_DRAWING;
SET COLOR_WIRE YELLOW;
SET COLOR_PROP ORANGE;
SET COLOR_DOT WHITE;
SET COLOR_ARC YELLOW;
SET COLOR_BODY GREEN;
SET COLOR_NOTE PURPLE;
SET PROP_DISPLAY VALUE;
SET PAGE_NUMBER P103;
FORCEADD OFFPAGE..5
(-8075 1950);
FORCEPROP 2 LAST $XR0 43 
J 0
(-8329 1950);
DISPLAY 0.638298 (-8329 1950);
PAINT MONO (-8329 1950);
FORCEPROP 2 LAST CDS_LIB mstr_standard
J 0
(-8075 1950);
DISPLAY 0.808511 (-8075 1950);
DISPLAY INVISIBLE (-8075 1950);
FORCEPROP 1 LAST OFFPAGE TRUE
J 0
(-7750 1825);
DISPLAY 0.872340 (-7750 1825);
PAINT GREEN (-7750 1825);
DISPLAY INVISIBLE (-7750 1825);
FORCEPROP 1 LAST COMMENT_BODY TRUE
J 0
(-7975 1875);
DISPLAY 0.872340 (-7975 1875);
PAINT GREEN (-7975 1875);
DISPLAY INVISIBLE (-7975 1875);
FORCEPROP 2 LAST PATH I1
J 0
(-8325 2000);
DISPLAY 1.021277 (-8325 2000);
DISPLAY INVISIBLE (-8325 2000);
FORCEADD OFFPAGE..6
(-8075 3550);
FORCEPROP 2 LAST $XR0 43 
J 0
(-8324 3550);
DISPLAY 0.638298 (-8324 3550);
PAINT MONO (-8324 3550);
FORCEPROP 2 LAST CDS_LIB mstr_standard
J 0
(-8075 3550);
DISPLAY 0.723404 (-8075 3550);
PAINT MONO (-8075 3550);
DISPLAY INVISIBLE (-8075 3550);
FORCEPROP 1 LAST OFFPAGE TRUE
J 0
(-7750 3425);
DISPLAY 0.872340 (-7750 3425);
PAINT GREEN (-7750 3425);
DISPLAY INVISIBLE (-7750 3425);
FORCEPROP 1 LAST COMMENT_BODY TRUE
J 0
(-7975 3475);
DISPLAY 0.872340 (-7975 3475);
PAINT GREEN (-7975 3475);
DISPLAY INVISIBLE (-7975 3475);
FORCEPROP 2 LAST PATH I10
J 0
(-8350 3600);
DISPLAY 1.021277 (-8350 3600);
DISPLAY INVISIBLE (-8350 3600);
FORCEADD TAP..1
(-5775 4100);
FORCEPROP 3 LASTPIN (-5825 4100) SIG_NAME M_G_CPU1_SA_DQ<6>
J 0
(-5815 4110);
DISPLAY 0.659574 (-5815 4110);
PAINT MONO (-5815 4110);
DISPLAY INVISIBLE (-5815 4110);
FORCEPROP 1 LASTPIN (-5825 4100) BN 6
J 0
(-5837 4108);
DISPLAY 0.489362 (-5837 4108);
PAINT GREEN (-5837 4108);
FORCEPROP 2 LAST CDS_LIB mstr_standard
J 0
(-5775 4100);
DISPLAY 0.723404 (-5775 4100);
PAINT MONO (-5775 4100);
DISPLAY INVISIBLE (-5775 4100);
FORCEPROP 1 LAST BODY_TYPE PLUMBING
J 0
(-5775 4150);
DISPLAY 0.872340 (-5775 4150);
PAINT GREEN (-5775 4150);
DISPLAY INVISIBLE (-5775 4150);
FORCEPROP 1 LAST HDL_TAP TRUE
J 0
(-5450 3975);
DISPLAY 0.872340 (-5450 3975);
DISPLAY INVISIBLE (-5450 3975);
FORCEPROP 1 LAST PATH I100
J 0
(-5777 4100);
DISPLAY 0.872340 (-5777 4100);
PAINT GREEN (-5777 4100);
DISPLAY INVISIBLE (-5777 4100);
FORCEADD TAP..1
(-5775 4250);
FORCEPROP 3 LASTPIN (-5825 4250) SIG_NAME M_G_CPU1_SA_DQ<9>
J 0
(-5815 4260);
DISPLAY 0.659574 (-5815 4260);
PAINT MONO (-5815 4260);
DISPLAY INVISIBLE (-5815 4260);
FORCEPROP 1 LASTPIN (-5825 4250) BN 9
J 0
(-5837 4258);
DISPLAY 0.489362 (-5837 4258);
PAINT GREEN (-5837 4258);
FORCEPROP 2 LAST CDS_LIB mstr_standard
J 0
(-5775 4250);
DISPLAY 0.723404 (-5775 4250);
PAINT MONO (-5775 4250);
DISPLAY INVISIBLE (-5775 4250);
FORCEPROP 1 LAST BODY_TYPE PLUMBING
J 0
(-5775 4300);
DISPLAY 0.872340 (-5775 4300);
PAINT GREEN (-5775 4300);
DISPLAY INVISIBLE (-5775 4300);
FORCEPROP 1 LAST HDL_TAP TRUE
J 0
(-5450 4125);
DISPLAY 0.872340 (-5450 4125);
DISPLAY INVISIBLE (-5450 4125);
FORCEPROP 1 LAST PATH I101
J 0
(-5777 4250);
DISPLAY 0.872340 (-5777 4250);
PAINT GREEN (-5777 4250);
DISPLAY INVISIBLE (-5777 4250);
FORCEADD TAP..1
(-5775 4200);
FORCEPROP 3 LASTPIN (-5825 4200) SIG_NAME M_G_CPU1_SA_DQ<8>
J 0
(-5815 4210);
DISPLAY 0.659574 (-5815 4210);
PAINT MONO (-5815 4210);
DISPLAY INVISIBLE (-5815 4210);
FORCEPROP 1 LASTPIN (-5825 4200) BN 8
J 0
(-5837 4208);
DISPLAY 0.489362 (-5837 4208);
PAINT GREEN (-5837 4208);
FORCEPROP 2 LAST CDS_LIB mstr_standard
J 0
(-5775 4200);
DISPLAY 0.723404 (-5775 4200);
PAINT MONO (-5775 4200);
DISPLAY INVISIBLE (-5775 4200);
FORCEPROP 1 LAST BODY_TYPE PLUMBING
J 0
(-5775 4250);
DISPLAY 0.872340 (-5775 4250);
PAINT GREEN (-5775 4250);
DISPLAY INVISIBLE (-5775 4250);
FORCEPROP 1 LAST HDL_TAP TRUE
J 0
(-5450 4075);
DISPLAY 0.872340 (-5450 4075);
DISPLAY INVISIBLE (-5450 4075);
FORCEPROP 1 LAST PATH I102
J 0
(-5777 4200);
DISPLAY 0.872340 (-5777 4200);
PAINT GREEN (-5777 4200);
DISPLAY INVISIBLE (-5777 4200);
FORCEADD TAP..1
(-5775 4050);
FORCEPROP 3 LASTPIN (-5825 4050) SIG_NAME M_G_CPU1_SA_DQ<5>
J 0
(-5815 4060);
DISPLAY 0.659574 (-5815 4060);
PAINT MONO (-5815 4060);
DISPLAY INVISIBLE (-5815 4060);
FORCEPROP 1 LASTPIN (-5825 4050) BN 5
J 0
(-5837 4058);
DISPLAY 0.489362 (-5837 4058);
PAINT GREEN (-5837 4058);
FORCEPROP 2 LAST CDS_LIB mstr_standard
J 0
(-5775 4050);
DISPLAY 0.723404 (-5775 4050);
PAINT MONO (-5775 4050);
DISPLAY INVISIBLE (-5775 4050);
FORCEPROP 1 LAST BODY_TYPE PLUMBING
J 0
(-5775 4100);
DISPLAY 0.872340 (-5775 4100);
PAINT GREEN (-5775 4100);
DISPLAY INVISIBLE (-5775 4100);
FORCEPROP 1 LAST HDL_TAP TRUE
J 0
(-5450 3925);
DISPLAY 0.872340 (-5450 3925);
DISPLAY INVISIBLE (-5450 3925);
FORCEPROP 1 LAST PATH I103
J 0
(-5777 4050);
DISPLAY 0.872340 (-5777 4050);
PAINT GREEN (-5777 4050);
DISPLAY INVISIBLE (-5777 4050);
FORCEADD TAP..1
(-5775 4450);
FORCEPROP 3 LASTPIN (-5825 4450) SIG_NAME M_G_CPU1_SA_DQ<13>
J 0
(-5815 4460);
DISPLAY 0.659574 (-5815 4460);
PAINT MONO (-5815 4460);
DISPLAY INVISIBLE (-5815 4460);
FORCEPROP 1 LASTPIN (-5825 4450) BN 13
J 0
(-5837 4458);
DISPLAY 0.489362 (-5837 4458);
PAINT GREEN (-5837 4458);
FORCEPROP 2 LAST CDS_LIB mstr_standard
J 0
(-5775 4450);
DISPLAY 0.723404 (-5775 4450);
PAINT MONO (-5775 4450);
DISPLAY INVISIBLE (-5775 4450);
FORCEPROP 1 LAST BODY_TYPE PLUMBING
J 0
(-5775 4500);
DISPLAY 0.872340 (-5775 4500);
PAINT GREEN (-5775 4500);
DISPLAY INVISIBLE (-5775 4500);
FORCEPROP 1 LAST HDL_TAP TRUE
J 0
(-5450 4325);
DISPLAY 0.872340 (-5450 4325);
DISPLAY INVISIBLE (-5450 4325);
FORCEPROP 1 LAST PATH I104
J 0
(-5777 4450);
DISPLAY 0.872340 (-5777 4450);
PAINT GREEN (-5777 4450);
DISPLAY INVISIBLE (-5777 4450);
FORCEADD TAP..1
(-5775 4500);
FORCEPROP 3 LASTPIN (-5825 4500) SIG_NAME M_G_CPU1_SA_DQ<14>
J 0
(-5815 4510);
DISPLAY 0.659574 (-5815 4510);
PAINT MONO (-5815 4510);
DISPLAY INVISIBLE (-5815 4510);
FORCEPROP 1 LASTPIN (-5825 4500) BN 14
J 0
(-5837 4508);
DISPLAY 0.489362 (-5837 4508);
PAINT GREEN (-5837 4508);
FORCEPROP 2 LAST CDS_LIB mstr_standard
J 0
(-5775 4500);
DISPLAY 0.723404 (-5775 4500);
PAINT MONO (-5775 4500);
DISPLAY INVISIBLE (-5775 4500);
FORCEPROP 1 LAST BODY_TYPE PLUMBING
J 0
(-5775 4550);
DISPLAY 0.872340 (-5775 4550);
PAINT GREEN (-5775 4550);
DISPLAY INVISIBLE (-5775 4550);
FORCEPROP 1 LAST HDL_TAP TRUE
J 0
(-5450 4375);
DISPLAY 0.872340 (-5450 4375);
DISPLAY INVISIBLE (-5450 4375);
FORCEPROP 1 LAST PATH I105
J 0
(-5777 4500);
DISPLAY 0.872340 (-5777 4500);
PAINT GREEN (-5777 4500);
DISPLAY INVISIBLE (-5777 4500);
FORCEADD TAP..1
(-5775 4300);
FORCEPROP 3 LASTPIN (-5825 4300) SIG_NAME M_G_CPU1_SA_DQ<10>
J 0
(-5815 4310);
DISPLAY 0.659574 (-5815 4310);
PAINT MONO (-5815 4310);
DISPLAY INVISIBLE (-5815 4310);
FORCEPROP 1 LASTPIN (-5825 4300) BN 10
J 0
(-5837 4308);
DISPLAY 0.489362 (-5837 4308);
PAINT GREEN (-5837 4308);
FORCEPROP 2 LAST CDS_LIB mstr_standard
J 0
(-5775 4300);
DISPLAY 0.723404 (-5775 4300);
PAINT MONO (-5775 4300);
DISPLAY INVISIBLE (-5775 4300);
FORCEPROP 1 LAST BODY_TYPE PLUMBING
J 0
(-5775 4350);
DISPLAY 0.872340 (-5775 4350);
PAINT GREEN (-5775 4350);
DISPLAY INVISIBLE (-5775 4350);
FORCEPROP 1 LAST HDL_TAP TRUE
J 0
(-5450 4175);
DISPLAY 0.872340 (-5450 4175);
DISPLAY INVISIBLE (-5450 4175);
FORCEPROP 1 LAST PATH I106
J 0
(-5777 4300);
DISPLAY 0.872340 (-5777 4300);
PAINT GREEN (-5777 4300);
DISPLAY INVISIBLE (-5777 4300);
FORCEADD TAP..1
(-5775 4350);
FORCEPROP 3 LASTPIN (-5825 4350) SIG_NAME M_G_CPU1_SA_DQ<11>
J 0
(-5815 4360);
DISPLAY 0.659574 (-5815 4360);
PAINT MONO (-5815 4360);
DISPLAY INVISIBLE (-5815 4360);
FORCEPROP 1 LASTPIN (-5825 4350) BN 11
J 0
(-5837 4358);
DISPLAY 0.489362 (-5837 4358);
PAINT GREEN (-5837 4358);
FORCEPROP 2 LAST CDS_LIB mstr_standard
J 0
(-5775 4350);
DISPLAY 0.723404 (-5775 4350);
PAINT MONO (-5775 4350);
DISPLAY INVISIBLE (-5775 4350);
FORCEPROP 1 LAST BODY_TYPE PLUMBING
J 0
(-5775 4400);
DISPLAY 0.872340 (-5775 4400);
PAINT GREEN (-5775 4400);
DISPLAY INVISIBLE (-5775 4400);
FORCEPROP 1 LAST HDL_TAP TRUE
J 0
(-5450 4225);
DISPLAY 0.872340 (-5450 4225);
DISPLAY INVISIBLE (-5450 4225);
FORCEPROP 1 LAST PATH I107
J 0
(-5777 4350);
DISPLAY 0.872340 (-5777 4350);
PAINT GREEN (-5777 4350);
DISPLAY INVISIBLE (-5777 4350);
FORCEADD TAP..1
(-5775 4400);
FORCEPROP 3 LASTPIN (-5825 4400) SIG_NAME M_G_CPU1_SA_DQ<12>
J 0
(-5815 4410);
DISPLAY 0.659574 (-5815 4410);
PAINT MONO (-5815 4410);
DISPLAY INVISIBLE (-5815 4410);
FORCEPROP 1 LASTPIN (-5825 4400) BN 12
J 0
(-5837 4408);
DISPLAY 0.489362 (-5837 4408);
PAINT GREEN (-5837 4408);
FORCEPROP 2 LAST CDS_LIB mstr_standard
J 0
(-5775 4400);
DISPLAY 0.723404 (-5775 4400);
PAINT MONO (-5775 4400);
DISPLAY INVISIBLE (-5775 4400);
FORCEPROP 1 LAST BODY_TYPE PLUMBING
J 0
(-5775 4450);
DISPLAY 0.872340 (-5775 4450);
PAINT GREEN (-5775 4450);
DISPLAY INVISIBLE (-5775 4450);
FORCEPROP 1 LAST HDL_TAP TRUE
J 0
(-5450 4275);
DISPLAY 0.872340 (-5450 4275);
DISPLAY INVISIBLE (-5450 4275);
FORCEPROP 1 LAST PATH I108
J 0
(-5777 4400);
DISPLAY 0.872340 (-5777 4400);
PAINT GREEN (-5777 4400);
DISPLAY INVISIBLE (-5777 4400);
FORCEADD TAP..1
(-5775 4700);
FORCEPROP 3 LASTPIN (-5825 4700) SIG_NAME M_G_CPU1_SA_DQ<18>
J 0
(-5815 4710);
DISPLAY 0.659574 (-5815 4710);
PAINT MONO (-5815 4710);
DISPLAY INVISIBLE (-5815 4710);
FORCEPROP 1 LASTPIN (-5825 4700) BN 18
J 0
(-5837 4708);
DISPLAY 0.489362 (-5837 4708);
PAINT GREEN (-5837 4708);
FORCEPROP 2 LAST CDS_LIB mstr_standard
J 0
(-5775 4700);
DISPLAY 0.723404 (-5775 4700);
PAINT MONO (-5775 4700);
DISPLAY INVISIBLE (-5775 4700);
FORCEPROP 1 LAST BODY_TYPE PLUMBING
J 0
(-5775 4750);
DISPLAY 0.872340 (-5775 4750);
PAINT GREEN (-5775 4750);
DISPLAY INVISIBLE (-5775 4750);
FORCEPROP 1 LAST HDL_TAP TRUE
J 0
(-5450 4575);
DISPLAY 0.872340 (-5450 4575);
DISPLAY INVISIBLE (-5450 4575);
FORCEPROP 1 LAST PATH I109
J 0
(-5777 4700);
DISPLAY 0.872340 (-5777 4700);
PAINT GREEN (-5777 4700);
DISPLAY INVISIBLE (-5777 4700);
FORCEADD OFFPAGE..6
(-8075 4000);
FORCEPROP 2 LAST $XR0 43 
J 0
(-8324 4000);
DISPLAY 0.638298 (-8324 4000);
PAINT MONO (-8324 4000);
FORCEPROP 2 LAST CDS_LIB mstr_standard
J 0
(-8075 4000);
DISPLAY 0.723404 (-8075 4000);
PAINT MONO (-8075 4000);
DISPLAY INVISIBLE (-8075 4000);
FORCEPROP 1 LAST OFFPAGE TRUE
J 0
(-7750 3875);
DISPLAY 0.872340 (-7750 3875);
PAINT GREEN (-7750 3875);
DISPLAY INVISIBLE (-7750 3875);
FORCEPROP 1 LAST COMMENT_BODY TRUE
J 0
(-7975 3925);
DISPLAY 0.872340 (-7975 3925);
PAINT GREEN (-7975 3925);
DISPLAY INVISIBLE (-7975 3925);
FORCEPROP 2 LAST PATH I11
J 0
(-8350 4050);
DISPLAY 1.021277 (-8350 4050);
DISPLAY INVISIBLE (-8350 4050);
FORCEADD TAP..1
(-5775 4750);
FORCEPROP 3 LASTPIN (-5825 4750) SIG_NAME M_G_CPU1_SA_DQ<19>
J 0
(-5815 4760);
DISPLAY 0.659574 (-5815 4760);
PAINT MONO (-5815 4760);
DISPLAY INVISIBLE (-5815 4760);
FORCEPROP 1 LASTPIN (-5825 4750) BN 19
J 0
(-5837 4758);
DISPLAY 0.489362 (-5837 4758);
PAINT GREEN (-5837 4758);
FORCEPROP 2 LAST CDS_LIB mstr_standard
J 0
(-5775 4750);
DISPLAY 0.723404 (-5775 4750);
PAINT MONO (-5775 4750);
DISPLAY INVISIBLE (-5775 4750);
FORCEPROP 1 LAST BODY_TYPE PLUMBING
J 0
(-5775 4800);
DISPLAY 0.872340 (-5775 4800);
PAINT GREEN (-5775 4800);
DISPLAY INVISIBLE (-5775 4800);
FORCEPROP 1 LAST HDL_TAP TRUE
J 0
(-5450 4625);
DISPLAY 0.872340 (-5450 4625);
DISPLAY INVISIBLE (-5450 4625);
FORCEPROP 1 LAST PATH I110
J 0
(-5777 4750);
DISPLAY 0.872340 (-5777 4750);
PAINT GREEN (-5777 4750);
DISPLAY INVISIBLE (-5777 4750);
FORCEADD TAP..1
(-5775 4550);
FORCEPROP 3 LASTPIN (-5825 4550) SIG_NAME M_G_CPU1_SA_DQ<15>
J 0
(-5815 4560);
DISPLAY 0.659574 (-5815 4560);
PAINT MONO (-5815 4560);
DISPLAY INVISIBLE (-5815 4560);
FORCEPROP 1 LASTPIN (-5825 4550) BN 15
J 0
(-5837 4558);
DISPLAY 0.489362 (-5837 4558);
PAINT GREEN (-5837 4558);
FORCEPROP 2 LAST CDS_LIB mstr_standard
J 0
(-5775 4550);
DISPLAY 0.723404 (-5775 4550);
PAINT MONO (-5775 4550);
DISPLAY INVISIBLE (-5775 4550);
FORCEPROP 1 LAST BODY_TYPE PLUMBING
J 0
(-5775 4600);
DISPLAY 0.872340 (-5775 4600);
PAINT GREEN (-5775 4600);
DISPLAY INVISIBLE (-5775 4600);
FORCEPROP 1 LAST HDL_TAP TRUE
J 0
(-5450 4425);
DISPLAY 0.872340 (-5450 4425);
DISPLAY INVISIBLE (-5450 4425);
FORCEPROP 1 LAST PATH I111
J 0
(-5777 4550);
DISPLAY 0.872340 (-5777 4550);
PAINT GREEN (-5777 4550);
DISPLAY INVISIBLE (-5777 4550);
FORCEADD TAP..1
(-5775 4600);
FORCEPROP 3 LASTPIN (-5825 4600) SIG_NAME M_G_CPU1_SA_DQ<16>
J 0
(-5815 4610);
DISPLAY 0.659574 (-5815 4610);
PAINT MONO (-5815 4610);
DISPLAY INVISIBLE (-5815 4610);
FORCEPROP 1 LASTPIN (-5825 4600) BN 16
J 0
(-5837 4608);
DISPLAY 0.489362 (-5837 4608);
PAINT GREEN (-5837 4608);
FORCEPROP 2 LAST CDS_LIB mstr_standard
J 0
(-5775 4600);
DISPLAY 0.723404 (-5775 4600);
PAINT MONO (-5775 4600);
DISPLAY INVISIBLE (-5775 4600);
FORCEPROP 1 LAST BODY_TYPE PLUMBING
J 0
(-5775 4650);
DISPLAY 0.872340 (-5775 4650);
PAINT GREEN (-5775 4650);
DISPLAY INVISIBLE (-5775 4650);
FORCEPROP 1 LAST HDL_TAP TRUE
J 0
(-5450 4475);
DISPLAY 0.872340 (-5450 4475);
DISPLAY INVISIBLE (-5450 4475);
FORCEPROP 1 LAST PATH I112
J 0
(-5777 4600);
DISPLAY 0.872340 (-5777 4600);
PAINT GREEN (-5777 4600);
DISPLAY INVISIBLE (-5777 4600);
FORCEADD TAP..1
(-5775 4650);
FORCEPROP 3 LASTPIN (-5825 4650) SIG_NAME M_G_CPU1_SA_DQ<17>
J 0
(-5815 4660);
DISPLAY 0.659574 (-5815 4660);
PAINT MONO (-5815 4660);
DISPLAY INVISIBLE (-5815 4660);
FORCEPROP 1 LASTPIN (-5825 4650) BN 17
J 0
(-5837 4658);
DISPLAY 0.489362 (-5837 4658);
PAINT GREEN (-5837 4658);
FORCEPROP 2 LAST CDS_LIB mstr_standard
J 0
(-5775 4650);
DISPLAY 0.723404 (-5775 4650);
PAINT MONO (-5775 4650);
DISPLAY INVISIBLE (-5775 4650);
FORCEPROP 1 LAST BODY_TYPE PLUMBING
J 0
(-5775 4700);
DISPLAY 0.872340 (-5775 4700);
PAINT GREEN (-5775 4700);
DISPLAY INVISIBLE (-5775 4700);
FORCEPROP 1 LAST HDL_TAP TRUE
J 0
(-5450 4525);
DISPLAY 0.872340 (-5450 4525);
DISPLAY INVISIBLE (-5450 4525);
FORCEPROP 1 LAST PATH I113
J 0
(-5777 4650);
DISPLAY 0.872340 (-5777 4650);
PAINT GREEN (-5777 4650);
DISPLAY INVISIBLE (-5777 4650);
FORCEADD TAP..1
(-5775 5000);
FORCEPROP 3 LASTPIN (-5825 5000) SIG_NAME M_G_CPU1_SA_DQ<24>
J 0
(-5815 5010);
DISPLAY 0.659574 (-5815 5010);
PAINT MONO (-5815 5010);
DISPLAY INVISIBLE (-5815 5010);
FORCEPROP 1 LASTPIN (-5825 5000) BN 24
J 0
(-5837 5008);
DISPLAY 0.489362 (-5837 5008);
PAINT GREEN (-5837 5008);
FORCEPROP 2 LAST CDS_LIB mstr_standard
J 0
(-5775 5000);
DISPLAY 0.723404 (-5775 5000);
PAINT MONO (-5775 5000);
DISPLAY INVISIBLE (-5775 5000);
FORCEPROP 1 LAST BODY_TYPE PLUMBING
J 0
(-5775 5050);
DISPLAY 0.872340 (-5775 5050);
PAINT GREEN (-5775 5050);
DISPLAY INVISIBLE (-5775 5050);
FORCEPROP 1 LAST HDL_TAP TRUE
J 0
(-5450 4875);
DISPLAY 0.872340 (-5450 4875);
DISPLAY INVISIBLE (-5450 4875);
FORCEPROP 1 LAST PATH I114
J 0
(-5777 5000);
DISPLAY 0.872340 (-5777 5000);
PAINT GREEN (-5777 5000);
DISPLAY INVISIBLE (-5777 5000);
FORCEADD TAP..1
(-5775 4950);
FORCEPROP 3 LASTPIN (-5825 4950) SIG_NAME M_G_CPU1_SA_DQ<23>
J 0
(-5815 4960);
DISPLAY 0.659574 (-5815 4960);
PAINT MONO (-5815 4960);
DISPLAY INVISIBLE (-5815 4960);
FORCEPROP 1 LASTPIN (-5825 4950) BN 23
J 0
(-5837 4958);
DISPLAY 0.489362 (-5837 4958);
PAINT GREEN (-5837 4958);
FORCEPROP 2 LAST CDS_LIB mstr_standard
J 0
(-5775 4950);
DISPLAY 0.723404 (-5775 4950);
PAINT MONO (-5775 4950);
DISPLAY INVISIBLE (-5775 4950);
FORCEPROP 1 LAST BODY_TYPE PLUMBING
J 0
(-5775 5000);
DISPLAY 0.872340 (-5775 5000);
PAINT GREEN (-5775 5000);
DISPLAY INVISIBLE (-5775 5000);
FORCEPROP 1 LAST HDL_TAP TRUE
J 0
(-5450 4825);
DISPLAY 0.872340 (-5450 4825);
DISPLAY INVISIBLE (-5450 4825);
FORCEPROP 1 LAST PATH I115
J 0
(-5777 4950);
DISPLAY 0.872340 (-5777 4950);
PAINT GREEN (-5777 4950);
DISPLAY INVISIBLE (-5777 4950);
FORCEADD TAP..1
(-5775 5050);
FORCEPROP 3 LASTPIN (-5825 5050) SIG_NAME M_G_CPU1_SA_DQ<25>
J 0
(-5815 5060);
DISPLAY 0.659574 (-5815 5060);
PAINT MONO (-5815 5060);
DISPLAY INVISIBLE (-5815 5060);
FORCEPROP 1 LASTPIN (-5825 5050) BN 25
J 0
(-5837 5058);
DISPLAY 0.489362 (-5837 5058);
PAINT GREEN (-5837 5058);
FORCEPROP 2 LAST CDS_LIB mstr_standard
J 0
(-5775 5050);
DISPLAY 0.723404 (-5775 5050);
PAINT MONO (-5775 5050);
DISPLAY INVISIBLE (-5775 5050);
FORCEPROP 1 LAST BODY_TYPE PLUMBING
J 0
(-5775 5100);
DISPLAY 0.872340 (-5775 5100);
PAINT GREEN (-5775 5100);
DISPLAY INVISIBLE (-5775 5100);
FORCEPROP 1 LAST HDL_TAP TRUE
J 0
(-5450 4925);
DISPLAY 0.872340 (-5450 4925);
DISPLAY INVISIBLE (-5450 4925);
FORCEPROP 1 LAST PATH I116
J 0
(-5777 5050);
DISPLAY 0.872340 (-5777 5050);
PAINT GREEN (-5777 5050);
DISPLAY INVISIBLE (-5777 5050);
FORCEADD TAP..1
(-5775 4800);
FORCEPROP 3 LASTPIN (-5825 4800) SIG_NAME M_G_CPU1_SA_DQ<20>
J 0
(-5815 4810);
DISPLAY 0.659574 (-5815 4810);
PAINT MONO (-5815 4810);
DISPLAY INVISIBLE (-5815 4810);
FORCEPROP 1 LASTPIN (-5825 4800) BN 20
J 0
(-5837 4808);
DISPLAY 0.489362 (-5837 4808);
PAINT GREEN (-5837 4808);
FORCEPROP 2 LAST CDS_LIB mstr_standard
J 0
(-5775 4800);
DISPLAY 0.723404 (-5775 4800);
PAINT MONO (-5775 4800);
DISPLAY INVISIBLE (-5775 4800);
FORCEPROP 1 LAST BODY_TYPE PLUMBING
J 0
(-5775 4850);
DISPLAY 0.872340 (-5775 4850);
PAINT GREEN (-5775 4850);
DISPLAY INVISIBLE (-5775 4850);
FORCEPROP 1 LAST HDL_TAP TRUE
J 0
(-5450 4675);
DISPLAY 0.872340 (-5450 4675);
DISPLAY INVISIBLE (-5450 4675);
FORCEPROP 1 LAST PATH I117
J 0
(-5777 4800);
DISPLAY 0.872340 (-5777 4800);
PAINT GREEN (-5777 4800);
DISPLAY INVISIBLE (-5777 4800);
FORCEADD TAP..1
(-5775 4850);
FORCEPROP 3 LASTPIN (-5825 4850) SIG_NAME M_G_CPU1_SA_DQ<21>
J 0
(-5815 4860);
DISPLAY 0.659574 (-5815 4860);
PAINT MONO (-5815 4860);
DISPLAY INVISIBLE (-5815 4860);
FORCEPROP 1 LASTPIN (-5825 4850) BN 21
J 0
(-5837 4858);
DISPLAY 0.489362 (-5837 4858);
PAINT GREEN (-5837 4858);
FORCEPROP 2 LAST CDS_LIB mstr_standard
J 0
(-5775 4850);
DISPLAY 0.723404 (-5775 4850);
PAINT MONO (-5775 4850);
DISPLAY INVISIBLE (-5775 4850);
FORCEPROP 1 LAST BODY_TYPE PLUMBING
J 0
(-5775 4900);
DISPLAY 0.872340 (-5775 4900);
PAINT GREEN (-5775 4900);
DISPLAY INVISIBLE (-5775 4900);
FORCEPROP 1 LAST HDL_TAP TRUE
J 0
(-5450 4725);
DISPLAY 0.872340 (-5450 4725);
DISPLAY INVISIBLE (-5450 4725);
FORCEPROP 1 LAST PATH I118
J 0
(-5777 4850);
DISPLAY 0.872340 (-5777 4850);
PAINT GREEN (-5777 4850);
DISPLAY INVISIBLE (-5777 4850);
FORCEADD TAP..1
(-5775 4900);
FORCEPROP 3 LASTPIN (-5825 4900) SIG_NAME M_G_CPU1_SA_DQ<22>
J 0
(-5815 4910);
DISPLAY 0.659574 (-5815 4910);
PAINT MONO (-5815 4910);
DISPLAY INVISIBLE (-5815 4910);
FORCEPROP 1 LASTPIN (-5825 4900) BN 22
J 0
(-5837 4908);
DISPLAY 0.489362 (-5837 4908);
PAINT GREEN (-5837 4908);
FORCEPROP 2 LAST CDS_LIB mstr_standard
J 0
(-5775 4900);
DISPLAY 0.723404 (-5775 4900);
PAINT MONO (-5775 4900);
DISPLAY INVISIBLE (-5775 4900);
FORCEPROP 1 LAST BODY_TYPE PLUMBING
J 0
(-5775 4950);
DISPLAY 0.872340 (-5775 4950);
PAINT GREEN (-5775 4950);
DISPLAY INVISIBLE (-5775 4950);
FORCEPROP 1 LAST HDL_TAP TRUE
J 0
(-5450 4775);
DISPLAY 0.872340 (-5450 4775);
DISPLAY INVISIBLE (-5450 4775);
FORCEPROP 1 LAST PATH I119
J 0
(-5777 4900);
DISPLAY 0.872340 (-5777 4900);
PAINT GREEN (-5777 4900);
DISPLAY INVISIBLE (-5777 4900);
FORCEADD OFFPAGE..1
(-8075 4050);
FORCEPROP 2 LAST $XR0 43 
J 0
(-8296 4050);
DISPLAY 0.638298 (-8296 4050);
PAINT MONO (-8296 4050);
FORCEPROP 2 LAST CDS_LIB mstr_standard
J 0
(-8075 4050);
DISPLAY 0.808511 (-8075 4050);
DISPLAY INVISIBLE (-8075 4050);
FORCEPROP 1 LAST OFFPAGE TRUE
J 0
(-7750 3925);
DISPLAY 0.872340 (-7750 3925);
PAINT GREEN (-7750 3925);
DISPLAY INVISIBLE (-7750 3925);
FORCEPROP 1 LAST COMMENT_BODY TRUE
J 0
(-7950 3950);
DISPLAY 0.872340 (-7950 3950);
PAINT GREEN (-7950 3950);
DISPLAY INVISIBLE (-7950 3950);
FORCEPROP 2 LAST PATH I12
J 0
(-8325 4100);
DISPLAY 1.021277 (-8325 4100);
DISPLAY INVISIBLE (-8325 4100);
FORCEADD TAP..1
(-5775 5300);
FORCEPROP 3 LASTPIN (-5825 5300) SIG_NAME M_G_CPU1_SA_DQ<30>
J 0
(-5815 5310);
DISPLAY 0.659574 (-5815 5310);
PAINT MONO (-5815 5310);
DISPLAY INVISIBLE (-5815 5310);
FORCEPROP 1 LASTPIN (-5825 5300) BN 30
J 0
(-5837 5308);
DISPLAY 0.489362 (-5837 5308);
PAINT GREEN (-5837 5308);
FORCEPROP 2 LAST CDS_LIB mstr_standard
J 0
(-5775 5300);
DISPLAY 0.723404 (-5775 5300);
PAINT MONO (-5775 5300);
DISPLAY INVISIBLE (-5775 5300);
FORCEPROP 1 LAST BODY_TYPE PLUMBING
J 0
(-5775 5350);
DISPLAY 0.872340 (-5775 5350);
PAINT GREEN (-5775 5350);
DISPLAY INVISIBLE (-5775 5350);
FORCEPROP 1 LAST HDL_TAP TRUE
J 0
(-5450 5175);
DISPLAY 0.872340 (-5450 5175);
DISPLAY INVISIBLE (-5450 5175);
FORCEPROP 1 LAST PATH I120
J 0
(-5777 5300);
DISPLAY 0.872340 (-5777 5300);
PAINT GREEN (-5777 5300);
DISPLAY INVISIBLE (-5777 5300);
FORCEADD TAP..1
(-5775 5200);
FORCEPROP 3 LASTPIN (-5825 5200) SIG_NAME M_G_CPU1_SA_DQ<28>
J 0
(-5815 5210);
DISPLAY 0.659574 (-5815 5210);
PAINT MONO (-5815 5210);
DISPLAY INVISIBLE (-5815 5210);
FORCEPROP 1 LASTPIN (-5825 5200) BN 28
J 0
(-5837 5208);
DISPLAY 0.489362 (-5837 5208);
PAINT GREEN (-5837 5208);
FORCEPROP 2 LAST CDS_LIB mstr_standard
J 0
(-5775 5200);
DISPLAY 0.723404 (-5775 5200);
PAINT MONO (-5775 5200);
DISPLAY INVISIBLE (-5775 5200);
FORCEPROP 1 LAST BODY_TYPE PLUMBING
J 0
(-5775 5250);
DISPLAY 0.872340 (-5775 5250);
PAINT GREEN (-5775 5250);
DISPLAY INVISIBLE (-5775 5250);
FORCEPROP 1 LAST HDL_TAP TRUE
J 0
(-5450 5075);
DISPLAY 0.872340 (-5450 5075);
DISPLAY INVISIBLE (-5450 5075);
FORCEPROP 1 LAST PATH I121
J 0
(-5777 5200);
DISPLAY 0.872340 (-5777 5200);
PAINT GREEN (-5777 5200);
DISPLAY INVISIBLE (-5777 5200);
FORCEADD TAP..1
(-5775 5250);
FORCEPROP 3 LASTPIN (-5825 5250) SIG_NAME M_G_CPU1_SA_DQ<29>
J 0
(-5815 5260);
DISPLAY 0.659574 (-5815 5260);
PAINT MONO (-5815 5260);
DISPLAY INVISIBLE (-5815 5260);
FORCEPROP 1 LASTPIN (-5825 5250) BN 29
J 0
(-5837 5258);
DISPLAY 0.489362 (-5837 5258);
PAINT GREEN (-5837 5258);
FORCEPROP 2 LAST CDS_LIB mstr_standard
J 0
(-5775 5250);
DISPLAY 0.723404 (-5775 5250);
PAINT MONO (-5775 5250);
DISPLAY INVISIBLE (-5775 5250);
FORCEPROP 1 LAST BODY_TYPE PLUMBING
J 0
(-5775 5300);
DISPLAY 0.872340 (-5775 5300);
PAINT GREEN (-5775 5300);
DISPLAY INVISIBLE (-5775 5300);
FORCEPROP 1 LAST HDL_TAP TRUE
J 0
(-5450 5125);
DISPLAY 0.872340 (-5450 5125);
DISPLAY INVISIBLE (-5450 5125);
FORCEPROP 1 LAST PATH I122
J 0
(-5777 5250);
DISPLAY 0.872340 (-5777 5250);
PAINT GREEN (-5777 5250);
DISPLAY INVISIBLE (-5777 5250);
FORCEADD TAP..1
(-5775 5150);
FORCEPROP 3 LASTPIN (-5825 5150) SIG_NAME M_G_CPU1_SA_DQ<27>
J 0
(-5815 5160);
DISPLAY 0.659574 (-5815 5160);
PAINT MONO (-5815 5160);
DISPLAY INVISIBLE (-5815 5160);
FORCEPROP 1 LASTPIN (-5825 5150) BN 27
J 0
(-5837 5158);
DISPLAY 0.489362 (-5837 5158);
PAINT GREEN (-5837 5158);
FORCEPROP 2 LAST CDS_LIB mstr_standard
J 0
(-5775 5150);
DISPLAY 0.723404 (-5775 5150);
PAINT MONO (-5775 5150);
DISPLAY INVISIBLE (-5775 5150);
FORCEPROP 1 LAST BODY_TYPE PLUMBING
J 0
(-5775 5200);
DISPLAY 0.872340 (-5775 5200);
PAINT GREEN (-5775 5200);
DISPLAY INVISIBLE (-5775 5200);
FORCEPROP 1 LAST HDL_TAP TRUE
J 0
(-5450 5025);
DISPLAY 0.872340 (-5450 5025);
DISPLAY INVISIBLE (-5450 5025);
FORCEPROP 1 LAST PATH I123
J 0
(-5777 5150);
DISPLAY 0.872340 (-5777 5150);
PAINT GREEN (-5777 5150);
DISPLAY INVISIBLE (-5777 5150);
FORCEADD TAP..1
(-5775 5100);
FORCEPROP 3 LASTPIN (-5825 5100) SIG_NAME M_G_CPU1_SA_DQ<26>
J 0
(-5815 5110);
DISPLAY 0.659574 (-5815 5110);
PAINT MONO (-5815 5110);
DISPLAY INVISIBLE (-5815 5110);
FORCEPROP 1 LASTPIN (-5825 5100) BN 26
J 0
(-5837 5108);
DISPLAY 0.489362 (-5837 5108);
PAINT GREEN (-5837 5108);
FORCEPROP 2 LAST CDS_LIB mstr_standard
J 0
(-5775 5100);
DISPLAY 0.723404 (-5775 5100);
PAINT MONO (-5775 5100);
DISPLAY INVISIBLE (-5775 5100);
FORCEPROP 1 LAST BODY_TYPE PLUMBING
J 0
(-5775 5150);
DISPLAY 0.872340 (-5775 5150);
PAINT GREEN (-5775 5150);
DISPLAY INVISIBLE (-5775 5150);
FORCEPROP 1 LAST HDL_TAP TRUE
J 0
(-5450 4975);
DISPLAY 0.872340 (-5450 4975);
DISPLAY INVISIBLE (-5450 4975);
FORCEPROP 1 LAST PATH I124
J 0
(-5777 5100);
DISPLAY 0.872340 (-5777 5100);
PAINT GREEN (-5777 5100);
DISPLAY INVISIBLE (-5777 5100);
FORCEADD TAP..1
(-5775 5350);
FORCEPROP 3 LASTPIN (-5825 5350) SIG_NAME M_G_CPU1_SA_DQ<31>
J 0
(-5815 5360);
DISPLAY 0.659574 (-5815 5360);
PAINT MONO (-5815 5360);
DISPLAY INVISIBLE (-5815 5360);
FORCEPROP 1 LASTPIN (-5825 5350) BN 31
J 0
(-5837 5358);
DISPLAY 0.489362 (-5837 5358);
PAINT GREEN (-5837 5358);
FORCEPROP 2 LAST CDS_LIB mstr_standard
J 0
(-5775 5350);
DISPLAY 0.723404 (-5775 5350);
PAINT MONO (-5775 5350);
DISPLAY INVISIBLE (-5775 5350);
FORCEPROP 1 LAST BODY_TYPE PLUMBING
J 0
(-5775 5400);
DISPLAY 0.872340 (-5775 5400);
PAINT GREEN (-5775 5400);
DISPLAY INVISIBLE (-5775 5400);
FORCEPROP 1 LAST HDL_TAP TRUE
J 0
(-5450 5225);
DISPLAY 0.872340 (-5450 5225);
DISPLAY INVISIBLE (-5450 5225);
FORCEPROP 1 LAST PATH I125
J 0
(-5777 5350);
DISPLAY 0.872340 (-5777 5350);
PAINT GREEN (-5777 5350);
DISPLAY INVISIBLE (-5777 5350);
FORCEADD OFFPAGE..3
(-5175 5400);
FORCEPROP 2 LAST $XR0 43 
J 0
(-4961 5400);
DISPLAY 0.638298 (-4961 5400);
PAINT MONO (-4961 5400);
FORCEPROP 2 LAST CDS_LIB mstr_standard
J 0
(-5175 5400);
DISPLAY 0.723404 (-5175 5400);
PAINT MONO (-5175 5400);
DISPLAY INVISIBLE (-5175 5400);
FORCEPROP 1 LAST OFFPAGE TRUE
J 0
(-4850 5275);
DISPLAY 0.872340 (-4850 5275);
PAINT GREEN (-4850 5275);
DISPLAY INVISIBLE (-4850 5275);
FORCEPROP 1 LAST COMMENT_BODY TRUE
J 0
(-5225 5300);
DISPLAY 0.872340 (-5225 5300);
PAINT GREEN (-5225 5300);
DISPLAY INVISIBLE (-5225 5300);
FORCEPROP 2 LAST PATH I126
J 0
(-4850 5450);
DISPLAY 1.021277 (-4850 5450);
DISPLAY INVISIBLE (-4850 5450);
FORCEADD OFFPAGE..5
(-6975 1300);
FORCEPROP 2 LAST $XR0 104 
J 0
(-7230 1300);
DISPLAY 0.638298 (-7230 1300);
PAINT MONO (-7230 1300);
FORCEPROP 2 LAST CDS_LIB mstr_standard
J 0
(-6975 1300);
DISPLAY 0.808511 (-6975 1300);
DISPLAY INVISIBLE (-6975 1300);
FORCEPROP 2 LAST BOM_COST MEM
J 0
(-7050 1375);
DISPLAY 0.808511 (-7050 1375);
DISPLAY INVISIBLE (-7050 1375);
FORCEPROP 1 LAST OFFPAGE TRUE
J 0
(-6650 1175);
DISPLAY 0.872340 (-6650 1175);
PAINT GREEN (-6650 1175);
DISPLAY INVISIBLE (-6650 1175);
FORCEPROP 1 LAST COMMENT_BODY TRUE
J 0
(-6875 1225);
DISPLAY 0.872340 (-6875 1225);
PAINT GREEN (-6875 1225);
DISPLAY INVISIBLE (-6875 1225);
FORCEPROP 2 LAST PATH I127
J 0
(-7225 1350);
DISPLAY 1.021277 (-7225 1350);
DISPLAY INVISIBLE (-7225 1350);
FORCEADD GND..1
(-6200 900);
FORCEPROP 3 LASTPIN (-6200 950) SIG_NAME GND\g
J 0
(-6190 960);
DISPLAY 0.659574 (-6190 960);
PAINT MONO (-6190 960);
DISPLAY INVISIBLE (-6190 960);
FORCEPROP 1 LAST VOLTAGE 0.0
J 0
(-6245 857);
DISPLAY 0.723404 (-6245 857);
PAINT SKYBLUE (-6245 857);
DISPLAY INVISIBLE (-6245 857);
FORCEPROP 2 LAST CDS_LIB mstr_symbols
J 0
(-6200 900);
DISPLAY 0.808511 (-6200 900);
DISPLAY INVISIBLE (-6200 900);
FORCEPROP 2 LAST BOM_COST MEM
J 0
(-6300 975);
DISPLAY 0.808511 (-6300 975);
DISPLAY INVISIBLE (-6300 975);
FORCEPROP 1 LAST SIZE 1B
J 0
(-6125 850);
DISPLAY 0.851064 (-6125 850);
PAINT GREEN (-6125 850);
DISPLAY INVISIBLE (-6125 850);
FORCEPROP 1 LAST BODY_TYPE PLUMBING
J 0
(-6245 857);
DISPLAY 0.340426 (-6245 857);
PAINT GREEN (-6245 857);
DISPLAY INVISIBLE (-6245 857);
FORCEPROP 1 LAST HDL_POWER GND
J 0
(-6200 1050);
DISPLAY 0.851064 (-6200 1050);
PAINT GREEN (-6200 1050);
DISPLAY INVISIBLE (-6200 1050);
FORCEPROP 1 LAST PATH I128
J 0
(-6125 900);
DISPLAY 0.872340 (-6125 900);
PAINT AQUA (-6125 900);
DISPLAY INVISIBLE (-6125 900);
FORCEADD Q_RES..2
(-6200 1125);
FORCEPROP 1 LAST LOCATION R37
J 0
(-6155 1250);
DISPLAY 0.489362 (-6155 1250);
PAINT SKYBLUE (-6155 1250);
FORCEPROP 2 LAST SEC 1
J 0
(-6150 1350);
DISPLAY 0.808511 (-6150 1350);
PAINT MONO (-6150 1350);
DISPLAY INVISIBLE (-6150 1350);
FORCEPROP 1 LASTPIN (-6200 1225) $PN 1
J 0
(-6195 1187);
DISPLAY 0.489362 (-6195 1187);
PAINT WHITE (-6195 1187);
FORCEPROP 1 LASTPIN (-6200 1025) $PN 2
J 0
(-6195 1035);
DISPLAY 0.489362 (-6195 1035);
PAINT WHITE (-6195 1035);
FORCEPROP 0 LASTPIN (-6200 1225) XNET_PINS 3
R 1
J 0
(-6210 1235);
DISPLAY 0.808511 (-6210 1235);
PAINT MONO (-6210 1235);
DISPLAY INVISIBLE (-6210 1235);
FORCEPROP 0 LASTPIN (-6200 1025) XNET_PINS 2
R 1
J 2
(-6210 1015);
DISPLAY 0.808511 (-6210 1015);
PAINT MONO (-6210 1015);
DISPLAY INVISIBLE (-6210 1015);
FORCEPROP 1 LAST VALUE 10K
J 0
(-6155 1200);
DISPLAY 0.489362 (-6155 1200);
PAINT SKYBLUE (-6155 1200);
FORCEPROP 1 LAST TOLERANCE 1%
J 0
(-6155 1150);
DISPLAY 0.489362 (-6155 1150);
PAINT SKYBLUE (-6155 1150);
FORCEPROP 1 LAST PACK_TYPE 0402LF
J 0
(-6160 950);
DISPLAY 0.489362 (-6160 950);
PAINT SKYBLUE (-6160 950);
FORCEPROP 1 LAST MATERIAL CHIP
J 0
(-6160 1050);
DISPLAY 0.489362 (-6160 1050);
PAINT SKYBLUE (-6160 1050);
FORCEPROP 1 LAST WATTAGE 1/16W
J 0
(-6160 1100);
DISPLAY 0.489362 (-6160 1100);
PAINT SKYBLUE (-6160 1100);
FORCEPROP 2 LAST SEC_TYPE 0402LF
J 0
(-6150 1350);
DISPLAY 0.808511 (-6150 1350);
PAINT MONO (-6150 1350);
DISPLAY INVISIBLE (-6150 1350);
FORCEPROP 2 LAST CDS_LIB pure_quanta
J 0
(-6200 1125);
DISPLAY INVISIBLE (-6200 1125);
FORCEPROP 2 LAST BOM_COST MEM
J 0
(-6150 1300);
DISPLAY 0.808511 (-6150 1300);
DISPLAY INVISIBLE (-6150 1300);
FORCEPROP 1 LAST PATH I129
J 0
(-6150 1300);
DISPLAY 0.978723 (-6150 1300);
PAINT WHITE (-6150 1300);
DISPLAY INVISIBLE (-6150 1300);
FORCEPROP 1 LAST PART_NUMBER CS31002FB08
J 0
(-6160 1000);
DISPLAY 0.489362 (-6160 1000);
PAINT SKYBLUE (-6160 1000);
DISPLAY INVISIBLE (-6160 1000);
FORCEADD OFFPAGE..1
(-8075 4100);
FORCEPROP 2 LAST $XR0 43 
J 0
(-8296 4100);
DISPLAY 0.638298 (-8296 4100);
PAINT MONO (-8296 4100);
FORCEPROP 2 LAST CDS_LIB mstr_standard
J 0
(-8075 4100);
DISPLAY 0.723404 (-8075 4100);
PAINT MONO (-8075 4100);
DISPLAY INVISIBLE (-8075 4100);
FORCEPROP 1 LAST OFFPAGE TRUE
J 0
(-7750 3975);
DISPLAY 0.872340 (-7750 3975);
PAINT GREEN (-7750 3975);
DISPLAY INVISIBLE (-7750 3975);
FORCEPROP 1 LAST COMMENT_BODY TRUE
J 0
(-7950 4000);
DISPLAY 0.872340 (-7950 4000);
PAINT GREEN (-7950 4000);
DISPLAY INVISIBLE (-7950 4000);
FORCEPROP 2 LAST PATH I13
J 0
(-8325 4150);
DISPLAY 1.021277 (-8325 4150);
DISPLAY INVISIBLE (-8325 4150);
FORCEADD OFFPAGE..1
(-8075 4250);
FORCEPROP 2 LAST $XR0 43 
J 0
(-8296 4250);
DISPLAY 0.638298 (-8296 4250);
PAINT MONO (-8296 4250);
FORCEPROP 2 LAST CDS_LIB mstr_standard
J 0
(-8075 4250);
DISPLAY 0.723404 (-8075 4250);
PAINT MONO (-8075 4250);
DISPLAY INVISIBLE (-8075 4250);
FORCEPROP 1 LAST OFFPAGE TRUE
J 0
(-7750 4125);
DISPLAY 0.872340 (-7750 4125);
PAINT GREEN (-7750 4125);
DISPLAY INVISIBLE (-7750 4125);
FORCEPROP 1 LAST COMMENT_BODY TRUE
J 0
(-7950 4150);
DISPLAY 0.872340 (-7950 4150);
PAINT GREEN (-7950 4150);
DISPLAY INVISIBLE (-7950 4150);
FORCEPROP 2 LAST PATH I14
J 0
(-8325 4300);
DISPLAY 1.021277 (-8325 4300);
DISPLAY INVISIBLE (-8325 4300);
FORCEADD GND..1
(-2125 1875);
FORCEPROP 3 LASTPIN (-2125 1925) SIG_NAME GND\g
J 0
(-2115 1935);
DISPLAY 0.659574 (-2115 1935);
PAINT MONO (-2115 1935);
DISPLAY INVISIBLE (-2115 1935);
FORCEPROP 1 LAST VOLTAGE 0.0
J 0
(-2170 1832);
DISPLAY 0.723404 (-2170 1832);
PAINT SKYBLUE (-2170 1832);
DISPLAY INVISIBLE (-2170 1832);
FORCEPROP 1 LAST SIZE 1B
J 0
(-2050 1825);
DISPLAY 0.851064 (-2050 1825);
PAINT GREEN (-2050 1825);
DISPLAY INVISIBLE (-2050 1825);
FORCEPROP 2 LAST CDS_LIB mstr_symbols
J 0
(-2125 1875);
DISPLAY 0.723404 (-2125 1875);
DISPLAY INVISIBLE (-2125 1875);
FORCEPROP 1 LAST BODY_TYPE PLUMBING
J 0
(-2170 1832);
DISPLAY 0.340426 (-2170 1832);
PAINT GREEN (-2170 1832);
DISPLAY INVISIBLE (-2170 1832);
FORCEPROP 1 LAST HDL_POWER GND
J 0
(-2125 2025);
DISPLAY 0.851064 (-2125 2025);
PAINT GREEN (-2125 2025);
DISPLAY INVISIBLE (-2125 2025);
FORCEPROP 1 LAST PATH I140
J 0
(-2050 1875);
DISPLAY 0.872340 (-2050 1875);
PAINT AQUA (-2050 1875);
DISPLAY INVISIBLE (-2050 1875);
FORCEADD GND..1
(-525 1675);
FORCEPROP 3 LASTPIN (-525 1725) SIG_NAME GND\g
J 0
(-515 1735);
DISPLAY 0.659574 (-515 1735);
PAINT MONO (-515 1735);
DISPLAY INVISIBLE (-515 1735);
FORCEPROP 1 LAST VOLTAGE 0.0
J 0
(-570 1632);
DISPLAY 0.723404 (-570 1632);
PAINT SKYBLUE (-570 1632);
DISPLAY INVISIBLE (-570 1632);
FORCEPROP 1 LAST SIZE 1B
J 0
(-450 1625);
DISPLAY 0.851064 (-450 1625);
PAINT GREEN (-450 1625);
DISPLAY INVISIBLE (-450 1625);
FORCEPROP 2 LAST CDS_LIB mstr_symbols
J 0
(-525 1675);
DISPLAY 0.723404 (-525 1675);
DISPLAY INVISIBLE (-525 1675);
FORCEPROP 1 LAST BODY_TYPE PLUMBING
J 0
(-570 1632);
DISPLAY 0.340426 (-570 1632);
PAINT GREEN (-570 1632);
DISPLAY INVISIBLE (-570 1632);
FORCEPROP 1 LAST HDL_POWER GND
J 0
(-525 1825);
DISPLAY 0.851064 (-525 1825);
PAINT GREEN (-525 1825);
DISPLAY INVISIBLE (-525 1825);
FORCEPROP 1 LAST PATH I141
J 0
(-450 1675);
DISPLAY 0.872340 (-450 1675);
PAINT AQUA (-450 1675);
DISPLAY INVISIBLE (-450 1675);
FORCEADD SCONN288_DDR506112002KQ..3
(-1325 3625);
FORCEPROP 1 LAST LOCATION J102
J 0
(-1775 5600);
DISPLAY 0.468085 (-1775 5600);
PAINT SKYBLUE (-1775 5600);
FORCEPROP 0 LAST $SEC 3
J 0
(-1775 5750);
DISPLAY 0.680851 (-1775 5750);
PAINT MONO (-1775 5750);
DISPLAY INVISIBLE (-1775 5750);
FORCEPROP 0 LAST CDS_SEC 3
J 0
(-1775 5750);
DISPLAY 0.680851 (-1775 5750);
DISPLAY INVISIBLE (-1775 5750);
FORCEPROP 0 LASTPIN (-725 2025) $PN G1
J 0
(-715 2035);
DISPLAY 0.680851 (-715 2035);
PAINT MONO (-715 2035);
FORCEPROP 0 LASTPIN (-725 1975) $PN G2
J 0
(-715 1985);
DISPLAY 0.680851 (-715 1985);
PAINT MONO (-715 1985);
FORCEPROP 0 LASTPIN (-725 1925) $PN G3
J 0
(-715 1935);
DISPLAY 0.680851 (-715 1935);
PAINT MONO (-715 1935);
FORCEPROP 0 LASTPIN (-1925 5175) $PN 1
J 2
(-1935 5185);
DISPLAY 0.680851 (-1935 5185);
PAINT MONO (-1935 5185);
FORCEPROP 0 LASTPIN (-1925 5225) $PN 145
J 2
(-1935 5235);
DISPLAY 0.680851 (-1935 5235);
PAINT MONO (-1935 5235);
FORCEPROP 0 LASTPIN (-1925 5275) $PN 146
J 2
(-1935 5285);
DISPLAY 0.680851 (-1935 5285);
PAINT MONO (-1935 5285);
FORCEPROP 0 LASTPIN (-725 2125) $PN 6
J 0
(-715 2135);
DISPLAY 0.680851 (-715 2135);
PAINT MONO (-715 2135);
FORCEPROP 0 LASTPIN (-725 2175) $PN 8
J 0
(-715 2185);
DISPLAY 0.680851 (-715 2185);
PAINT MONO (-715 2185);
FORCEPROP 0 LASTPIN (-725 2225) $PN 10
J 0
(-715 2235);
DISPLAY 0.680851 (-715 2235);
PAINT MONO (-715 2235);
FORCEPROP 0 LASTPIN (-725 2275) $PN 13
J 0
(-715 2285);
DISPLAY 0.680851 (-715 2285);
PAINT MONO (-715 2285);
FORCEPROP 0 LASTPIN (-725 2325) $PN 15
J 0
(-715 2335);
DISPLAY 0.680851 (-715 2335);
PAINT MONO (-715 2335);
FORCEPROP 0 LASTPIN (-725 2375) $PN 17
J 0
(-715 2385);
DISPLAY 0.680851 (-715 2385);
PAINT MONO (-715 2385);
FORCEPROP 0 LASTPIN (-725 2425) $PN 19
J 0
(-715 2435);
DISPLAY 0.680851 (-715 2435);
PAINT MONO (-715 2435);
FORCEPROP 0 LASTPIN (-725 2475) $PN 21
J 0
(-715 2485);
DISPLAY 0.680851 (-715 2485);
PAINT MONO (-715 2485);
FORCEPROP 0 LASTPIN (-725 2525) $PN 24
J 0
(-715 2535);
DISPLAY 0.680851 (-715 2535);
PAINT MONO (-715 2535);
FORCEPROP 0 LASTPIN (-725 2575) $PN 26
J 0
(-715 2585);
DISPLAY 0.680851 (-715 2585);
PAINT MONO (-715 2585);
FORCEPROP 0 LASTPIN (-725 2625) $PN 28
J 0
(-715 2635);
DISPLAY 0.680851 (-715 2635);
PAINT MONO (-715 2635);
FORCEPROP 0 LASTPIN (-725 2675) $PN 30
J 0
(-715 2685);
DISPLAY 0.680851 (-715 2685);
PAINT MONO (-715 2685);
FORCEPROP 0 LASTPIN (-725 2725) $PN 32
J 0
(-715 2735);
DISPLAY 0.680851 (-715 2735);
PAINT MONO (-715 2735);
FORCEPROP 0 LASTPIN (-725 2775) $PN 35
J 0
(-715 2785);
DISPLAY 0.680851 (-715 2785);
PAINT MONO (-715 2785);
FORCEPROP 0 LASTPIN (-725 2825) $PN 37
J 0
(-715 2835);
DISPLAY 0.680851 (-715 2835);
PAINT MONO (-715 2835);
FORCEPROP 0 LASTPIN (-725 2875) $PN 39
J 0
(-715 2885);
DISPLAY 0.680851 (-715 2885);
PAINT MONO (-715 2885);
FORCEPROP 0 LASTPIN (-725 2925) $PN 41
J 0
(-715 2935);
DISPLAY 0.680851 (-715 2935);
PAINT MONO (-715 2935);
FORCEPROP 0 LASTPIN (-725 2975) $PN 43
J 0
(-715 2985);
DISPLAY 0.680851 (-715 2985);
PAINT MONO (-715 2985);
FORCEPROP 0 LASTPIN (-725 3025) $PN 46
J 0
(-715 3035);
DISPLAY 0.680851 (-715 3035);
PAINT MONO (-715 3035);
FORCEPROP 0 LASTPIN (-725 3075) $PN 48
J 0
(-715 3085);
DISPLAY 0.680851 (-715 3085);
PAINT MONO (-715 3085);
FORCEPROP 0 LASTPIN (-725 3125) $PN 50
J 0
(-715 3135);
DISPLAY 0.680851 (-715 3135);
PAINT MONO (-715 3135);
FORCEPROP 0 LASTPIN (-725 3175) $PN 52
J 0
(-715 3185);
DISPLAY 0.680851 (-715 3185);
PAINT MONO (-715 3185);
FORCEPROP 0 LASTPIN (-725 3225) $PN 54
J 0
(-715 3235);
DISPLAY 0.680851 (-715 3235);
PAINT MONO (-715 3235);
FORCEPROP 0 LASTPIN (-725 3275) $PN 57
J 0
(-715 3285);
DISPLAY 0.680851 (-715 3285);
PAINT MONO (-715 3285);
FORCEPROP 0 LASTPIN (-725 3325) $PN 59
J 0
(-715 3335);
DISPLAY 0.680851 (-715 3335);
PAINT MONO (-715 3335);
FORCEPROP 0 LASTPIN (-725 3375) $PN 61
J 0
(-715 3385);
DISPLAY 0.680851 (-715 3385);
PAINT MONO (-715 3385);
FORCEPROP 0 LASTPIN (-725 3425) $PN 63
J 0
(-715 3435);
DISPLAY 0.680851 (-715 3435);
PAINT MONO (-715 3435);
FORCEPROP 0 LASTPIN (-725 3475) $PN 65
J 0
(-715 3485);
DISPLAY 0.680851 (-715 3485);
PAINT MONO (-715 3485);
FORCEPROP 0 LASTPIN (-725 3525) $PN 67
J 0
(-715 3535);
DISPLAY 0.680851 (-715 3535);
PAINT MONO (-715 3535);
FORCEPROP 0 LASTPIN (-725 3575) $PN 69
J 0
(-715 3585);
DISPLAY 0.680851 (-715 3585);
PAINT MONO (-715 3585);
FORCEPROP 0 LASTPIN (-725 3625) $PN 71
J 0
(-715 3635);
DISPLAY 0.680851 (-715 3635);
PAINT MONO (-715 3635);
FORCEPROP 0 LASTPIN (-725 3675) $PN 73
J 0
(-715 3685);
DISPLAY 0.680851 (-715 3685);
PAINT MONO (-715 3685);
FORCEPROP 0 LASTPIN (-725 3725) $PN 75
J 0
(-715 3735);
DISPLAY 0.680851 (-715 3735);
PAINT MONO (-715 3735);
FORCEPROP 0 LASTPIN (-725 3775) $PN 77
J 0
(-715 3785);
DISPLAY 0.680851 (-715 3785);
PAINT MONO (-715 3785);
FORCEPROP 0 LASTPIN (-725 3825) $PN 79
J 0
(-715 3835);
DISPLAY 0.680851 (-715 3835);
PAINT MONO (-715 3835);
FORCEPROP 0 LASTPIN (-725 3875) $PN 81
J 0
(-715 3885);
DISPLAY 0.680851 (-715 3885);
PAINT MONO (-715 3885);
FORCEPROP 0 LASTPIN (-725 3925) $PN 83
J 0
(-715 3935);
DISPLAY 0.680851 (-715 3935);
PAINT MONO (-715 3935);
FORCEPROP 0 LASTPIN (-725 3975) $PN 85
J 0
(-715 3985);
DISPLAY 0.680851 (-715 3985);
PAINT MONO (-715 3985);
FORCEPROP 0 LASTPIN (-725 4025) $PN 88
J 0
(-715 4035);
DISPLAY 0.680851 (-715 4035);
PAINT MONO (-715 4035);
FORCEPROP 0 LASTPIN (-725 4075) $PN 90
J 0
(-715 4085);
DISPLAY 0.680851 (-715 4085);
PAINT MONO (-715 4085);
FORCEPROP 0 LASTPIN (-725 4125) $PN 92
J 0
(-715 4135);
DISPLAY 0.680851 (-715 4135);
PAINT MONO (-715 4135);
FORCEPROP 0 LASTPIN (-725 4175) $PN 95
J 0
(-715 4185);
DISPLAY 0.680851 (-715 4185);
PAINT MONO (-715 4185);
FORCEPROP 0 LASTPIN (-725 4225) $PN 97
J 0
(-715 4235);
DISPLAY 0.680851 (-715 4235);
PAINT MONO (-715 4235);
FORCEPROP 0 LASTPIN (-725 4275) $PN 99
J 0
(-715 4285);
DISPLAY 0.680851 (-715 4285);
PAINT MONO (-715 4285);
FORCEPROP 0 LASTPIN (-725 4325) $PN 101
J 0
(-715 4335);
DISPLAY 0.680851 (-715 4335);
PAINT MONO (-715 4335);
FORCEPROP 0 LASTPIN (-725 4375) $PN 103
J 0
(-715 4385);
DISPLAY 0.680851 (-715 4385);
PAINT MONO (-715 4385);
FORCEPROP 0 LASTPIN (-725 4425) $PN 106
J 0
(-715 4435);
DISPLAY 0.680851 (-715 4435);
PAINT MONO (-715 4435);
FORCEPROP 0 LASTPIN (-725 4475) $PN 108
J 0
(-715 4485);
DISPLAY 0.680851 (-715 4485);
PAINT MONO (-715 4485);
FORCEPROP 0 LASTPIN (-725 4525) $PN 110
J 0
(-715 4535);
DISPLAY 0.680851 (-715 4535);
PAINT MONO (-715 4535);
FORCEPROP 0 LASTPIN (-725 4575) $PN 112
J 0
(-715 4585);
DISPLAY 0.680851 (-715 4585);
PAINT MONO (-715 4585);
FORCEPROP 0 LASTPIN (-725 4625) $PN 114
J 0
(-715 4635);
DISPLAY 0.680851 (-715 4635);
PAINT MONO (-715 4635);
FORCEPROP 0 LASTPIN (-725 4675) $PN 117
J 0
(-715 4685);
DISPLAY 0.680851 (-715 4685);
PAINT MONO (-715 4685);
FORCEPROP 0 LASTPIN (-725 4725) $PN 119
J 0
(-715 4735);
DISPLAY 0.680851 (-715 4735);
PAINT MONO (-715 4735);
FORCEPROP 0 LASTPIN (-725 4775) $PN 121
J 0
(-715 4785);
DISPLAY 0.680851 (-715 4785);
PAINT MONO (-715 4785);
FORCEPROP 0 LASTPIN (-725 4825) $PN 123
J 0
(-715 4835);
DISPLAY 0.680851 (-715 4835);
PAINT MONO (-715 4835);
FORCEPROP 0 LASTPIN (-725 4875) $PN 125
J 0
(-715 4885);
DISPLAY 0.680851 (-715 4885);
PAINT MONO (-715 4885);
FORCEPROP 0 LASTPIN (-725 4925) $PN 128
J 0
(-715 4935);
DISPLAY 0.680851 (-715 4935);
PAINT MONO (-715 4935);
FORCEPROP 0 LASTPIN (-725 4975) $PN 130
J 0
(-715 4985);
DISPLAY 0.680851 (-715 4985);
PAINT MONO (-715 4985);
FORCEPROP 0 LASTPIN (-725 5025) $PN 132
J 0
(-715 5035);
DISPLAY 0.680851 (-715 5035);
PAINT MONO (-715 5035);
FORCEPROP 0 LASTPIN (-725 5075) $PN 134
J 0
(-715 5085);
DISPLAY 0.680851 (-715 5085);
PAINT MONO (-715 5085);
FORCEPROP 0 LASTPIN (-725 5125) $PN 136
J 0
(-715 5135);
DISPLAY 0.680851 (-715 5135);
PAINT MONO (-715 5135);
FORCEPROP 0 LASTPIN (-725 5175) $PN 139
J 0
(-715 5185);
DISPLAY 0.680851 (-715 5185);
PAINT MONO (-715 5185);
FORCEPROP 0 LASTPIN (-725 5225) $PN 141
J 0
(-715 5235);
DISPLAY 0.680851 (-715 5235);
PAINT MONO (-715 5235);
FORCEPROP 0 LASTPIN (-725 5275) $PN 143
J 0
(-715 5285);
DISPLAY 0.680851 (-715 5285);
PAINT MONO (-715 5285);
FORCEPROP 0 LASTPIN (-1925 2025) $PN 151
J 2
(-1935 2035);
DISPLAY 0.680851 (-1935 2035);
PAINT MONO (-1935 2035);
FORCEPROP 0 LASTPIN (-1925 2075) $PN 153
J 2
(-1935 2085);
DISPLAY 0.680851 (-1935 2085);
PAINT MONO (-1935 2085);
FORCEPROP 0 LASTPIN (-1925 2125) $PN 155
J 2
(-1935 2135);
DISPLAY 0.680851 (-1935 2135);
PAINT MONO (-1935 2135);
FORCEPROP 0 LASTPIN (-1925 2175) $PN 158
J 2
(-1935 2185);
DISPLAY 0.680851 (-1935 2185);
PAINT MONO (-1935 2185);
FORCEPROP 0 LASTPIN (-1925 2225) $PN 160
J 2
(-1935 2235);
DISPLAY 0.680851 (-1935 2235);
PAINT MONO (-1935 2235);
FORCEPROP 0 LASTPIN (-1925 2275) $PN 162
J 2
(-1935 2285);
DISPLAY 0.680851 (-1935 2285);
PAINT MONO (-1935 2285);
FORCEPROP 0 LASTPIN (-1925 2325) $PN 164
J 2
(-1935 2335);
DISPLAY 0.680851 (-1935 2335);
PAINT MONO (-1935 2335);
FORCEPROP 0 LASTPIN (-1925 2375) $PN 166
J 2
(-1935 2385);
DISPLAY 0.680851 (-1935 2385);
PAINT MONO (-1935 2385);
FORCEPROP 0 LASTPIN (-1925 2425) $PN 169
J 2
(-1935 2435);
DISPLAY 0.680851 (-1935 2435);
PAINT MONO (-1935 2435);
FORCEPROP 0 LASTPIN (-1925 2475) $PN 171
J 2
(-1935 2485);
DISPLAY 0.680851 (-1935 2485);
PAINT MONO (-1935 2485);
FORCEPROP 0 LASTPIN (-1925 2525) $PN 173
J 2
(-1935 2535);
DISPLAY 0.680851 (-1935 2535);
PAINT MONO (-1935 2535);
FORCEPROP 0 LASTPIN (-1925 2575) $PN 175
J 2
(-1935 2585);
DISPLAY 0.680851 (-1935 2585);
PAINT MONO (-1935 2585);
FORCEPROP 0 LASTPIN (-1925 2625) $PN 177
J 2
(-1935 2635);
DISPLAY 0.680851 (-1935 2635);
PAINT MONO (-1935 2635);
FORCEPROP 0 LASTPIN (-1925 2675) $PN 180
J 2
(-1935 2685);
DISPLAY 0.680851 (-1935 2685);
PAINT MONO (-1935 2685);
FORCEPROP 0 LASTPIN (-1925 2725) $PN 182
J 2
(-1935 2735);
DISPLAY 0.680851 (-1935 2735);
PAINT MONO (-1935 2735);
FORCEPROP 0 LASTPIN (-1925 2775) $PN 184
J 2
(-1935 2785);
DISPLAY 0.680851 (-1935 2785);
PAINT MONO (-1935 2785);
FORCEPROP 0 LASTPIN (-1925 2825) $PN 186
J 2
(-1935 2835);
DISPLAY 0.680851 (-1935 2835);
PAINT MONO (-1935 2835);
FORCEPROP 0 LASTPIN (-1925 2875) $PN 188
J 2
(-1935 2885);
DISPLAY 0.680851 (-1935 2885);
PAINT MONO (-1935 2885);
FORCEPROP 0 LASTPIN (-1925 2925) $PN 191
J 2
(-1935 2935);
DISPLAY 0.680851 (-1935 2935);
PAINT MONO (-1935 2935);
FORCEPROP 0 LASTPIN (-1925 2975) $PN 193
J 2
(-1935 2985);
DISPLAY 0.680851 (-1935 2985);
PAINT MONO (-1935 2985);
FORCEPROP 0 LASTPIN (-1925 3025) $PN 195
J 2
(-1935 3035);
DISPLAY 0.680851 (-1935 3035);
PAINT MONO (-1935 3035);
FORCEPROP 0 LASTPIN (-1925 3075) $PN 197
J 2
(-1935 3085);
DISPLAY 0.680851 (-1935 3085);
PAINT MONO (-1935 3085);
FORCEPROP 0 LASTPIN (-1925 3125) $PN 199
J 2
(-1935 3135);
DISPLAY 0.680851 (-1935 3135);
PAINT MONO (-1935 3135);
FORCEPROP 0 LASTPIN (-1925 3175) $PN 202
J 2
(-1935 3185);
DISPLAY 0.680851 (-1935 3185);
PAINT MONO (-1935 3185);
FORCEPROP 0 LASTPIN (-1925 3225) $PN 204
J 2
(-1935 3235);
DISPLAY 0.680851 (-1935 3235);
PAINT MONO (-1935 3235);
FORCEPROP 0 LASTPIN (-1925 3275) $PN 206
J 2
(-1935 3285);
DISPLAY 0.680851 (-1935 3285);
PAINT MONO (-1935 3285);
FORCEPROP 0 LASTPIN (-1925 3325) $PN 208
J 2
(-1935 3335);
DISPLAY 0.680851 (-1935 3335);
PAINT MONO (-1935 3335);
FORCEPROP 0 LASTPIN (-1925 3375) $PN 210
J 2
(-1935 3385);
DISPLAY 0.680851 (-1935 3385);
PAINT MONO (-1935 3385);
FORCEPROP 0 LASTPIN (-1925 3425) $PN 212
J 2
(-1935 3435);
DISPLAY 0.680851 (-1935 3435);
PAINT MONO (-1935 3435);
FORCEPROP 0 LASTPIN (-1925 3475) $PN 214
J 2
(-1935 3485);
DISPLAY 0.680851 (-1935 3485);
PAINT MONO (-1935 3485);
FORCEPROP 0 LASTPIN (-1925 3525) $PN 216
J 2
(-1935 3535);
DISPLAY 0.680851 (-1935 3535);
PAINT MONO (-1935 3535);
FORCEPROP 0 LASTPIN (-1925 3575) $PN 219
J 2
(-1935 3585);
DISPLAY 0.680851 (-1935 3585);
PAINT MONO (-1935 3585);
FORCEPROP 0 LASTPIN (-1925 3625) $PN 222
J 2
(-1935 3635);
DISPLAY 0.680851 (-1935 3635);
PAINT MONO (-1935 3635);
FORCEPROP 0 LASTPIN (-1925 3675) $PN 224
J 2
(-1935 3685);
DISPLAY 0.680851 (-1935 3685);
PAINT MONO (-1935 3685);
FORCEPROP 0 LASTPIN (-1925 3725) $PN 226
J 2
(-1935 3735);
DISPLAY 0.680851 (-1935 3735);
PAINT MONO (-1935 3735);
FORCEPROP 0 LASTPIN (-1925 3775) $PN 228
J 2
(-1935 3785);
DISPLAY 0.680851 (-1935 3785);
PAINT MONO (-1935 3785);
FORCEPROP 0 LASTPIN (-1925 3825) $PN 230
J 2
(-1935 3835);
DISPLAY 0.680851 (-1935 3835);
PAINT MONO (-1935 3835);
FORCEPROP 0 LASTPIN (-1925 3875) $PN 233
J 2
(-1935 3885);
DISPLAY 0.680851 (-1935 3885);
PAINT MONO (-1935 3885);
FORCEPROP 0 LASTPIN (-1925 3925) $PN 235
J 2
(-1935 3935);
DISPLAY 0.680851 (-1935 3935);
PAINT MONO (-1935 3935);
FORCEPROP 0 LASTPIN (-1925 3975) $PN 237
J 2
(-1935 3985);
DISPLAY 0.680851 (-1935 3985);
PAINT MONO (-1935 3985);
FORCEPROP 0 LASTPIN (-1925 4025) $PN 240
J 2
(-1935 4035);
DISPLAY 0.680851 (-1935 4035);
PAINT MONO (-1935 4035);
FORCEPROP 0 LASTPIN (-1925 4075) $PN 242
J 2
(-1935 4085);
DISPLAY 0.680851 (-1935 4085);
PAINT MONO (-1935 4085);
FORCEPROP 0 LASTPIN (-1925 4125) $PN 244
J 2
(-1935 4135);
DISPLAY 0.680851 (-1935 4135);
PAINT MONO (-1935 4135);
FORCEPROP 0 LASTPIN (-1925 4175) $PN 246
J 2
(-1935 4185);
DISPLAY 0.680851 (-1935 4185);
PAINT MONO (-1935 4185);
FORCEPROP 0 LASTPIN (-1925 4225) $PN 248
J 2
(-1935 4235);
DISPLAY 0.680851 (-1935 4235);
PAINT MONO (-1935 4235);
FORCEPROP 0 LASTPIN (-1925 4275) $PN 251
J 2
(-1935 4285);
DISPLAY 0.680851 (-1935 4285);
PAINT MONO (-1935 4285);
FORCEPROP 0 LASTPIN (-1925 4325) $PN 253
J 2
(-1935 4335);
DISPLAY 0.680851 (-1935 4335);
PAINT MONO (-1935 4335);
FORCEPROP 0 LASTPIN (-1925 4375) $PN 255
J 2
(-1935 4385);
DISPLAY 0.680851 (-1935 4385);
PAINT MONO (-1935 4385);
FORCEPROP 0 LASTPIN (-1925 4425) $PN 257
J 2
(-1935 4435);
DISPLAY 0.680851 (-1935 4435);
PAINT MONO (-1935 4435);
FORCEPROP 0 LASTPIN (-1925 4475) $PN 259
J 2
(-1935 4485);
DISPLAY 0.680851 (-1935 4485);
PAINT MONO (-1935 4485);
FORCEPROP 0 LASTPIN (-1925 4525) $PN 262
J 2
(-1935 4535);
DISPLAY 0.680851 (-1935 4535);
PAINT MONO (-1935 4535);
FORCEPROP 0 LASTPIN (-1925 4575) $PN 264
J 2
(-1935 4585);
DISPLAY 0.680851 (-1935 4585);
PAINT MONO (-1935 4585);
FORCEPROP 0 LASTPIN (-1925 4625) $PN 266
J 2
(-1935 4635);
DISPLAY 0.680851 (-1935 4635);
PAINT MONO (-1935 4635);
FORCEPROP 0 LASTPIN (-1925 4675) $PN 268
J 2
(-1935 4685);
DISPLAY 0.680851 (-1935 4685);
PAINT MONO (-1935 4685);
FORCEPROP 0 LASTPIN (-1925 4725) $PN 270
J 2
(-1935 4735);
DISPLAY 0.680851 (-1935 4735);
PAINT MONO (-1935 4735);
FORCEPROP 0 LASTPIN (-1925 4775) $PN 273
J 2
(-1935 4785);
DISPLAY 0.680851 (-1935 4785);
PAINT MONO (-1935 4785);
FORCEPROP 0 LASTPIN (-1925 4825) $PN 275
J 2
(-1935 4835);
DISPLAY 0.680851 (-1935 4835);
PAINT MONO (-1935 4835);
FORCEPROP 0 LASTPIN (-1925 4875) $PN 277
J 2
(-1935 4885);
DISPLAY 0.680851 (-1935 4885);
PAINT MONO (-1935 4885);
FORCEPROP 0 LASTPIN (-1925 4925) $PN 279
J 2
(-1935 4935);
DISPLAY 0.680851 (-1935 4935);
PAINT MONO (-1935 4935);
FORCEPROP 0 LASTPIN (-1925 4975) $PN 281
J 2
(-1935 4985);
DISPLAY 0.680851 (-1935 4985);
PAINT MONO (-1935 4985);
FORCEPROP 0 LASTPIN (-1925 5025) $PN 284
J 2
(-1935 5035);
DISPLAY 0.680851 (-1935 5035);
PAINT MONO (-1935 5035);
FORCEPROP 0 LASTPIN (-1925 5075) $PN 286
J 2
(-1935 5085);
DISPLAY 0.680851 (-1935 5085);
PAINT MONO (-1935 5085);
FORCEPROP 0 LASTPIN (-1925 5125) $PN 288
J 2
(-1935 5135);
DISPLAY 0.680851 (-1935 5135);
PAINT MONO (-1935 5135);
FORCEPROP 2 LAST VALUE SCONN288_DDR506112002KQ
J 0
(-1775 5650);
DISPLAY 0.489362 (-1775 5650);
PAINT SKYBLUE (-1775 5650);
FORCEPROP 1 LAST MATERIAL IO
J 0
(-1775 5450);
DISPLAY 0.468085 (-1775 5450);
PAINT SKYBLUE (-1775 5450);
FORCEPROP 2 LAST PART_TYPE SMLF
J 0
(-1775 5700);
DISPLAY 1.021277 (-1775 5700);
FORCEPROP 2 LAST CDS_LIB pure_quanta
J 0
(-1325 3625);
DISPLAY INVISIBLE (-1325 3625);
FORCEPROP 1 LAST NEEDS_NO_SIZE TRUE
J 0
(-1325 3625);
DISPLAY 0.723404 (-1325 3625);
PAINT GREEN (-1325 3625);
DISPLAY INVISIBLE (-1325 3625);
FORCEPROP 1 LAST CDS_LMAN_SYM_OUTLINE -450,1800,450,-1750
J 0
(-1325 3625);
DISPLAY 0.468085 (-1325 3625);
PAINT GREEN (-1325 3625);
DISPLAY INVISIBLE (-1325 3625);
FORCEPROP 1 LAST PATH I142
J 0
(-1325 3625);
DISPLAY 0.723404 (-1325 3625);
PAINT GREEN (-1325 3625);
DISPLAY INVISIBLE (-1325 3625);
FORCEPROP 1 LAST PART_NUMBER DFHST8FS479
J 0
(-1775 5525);
DISPLAY 0.468085 (-1775 5525);
PAINT SKYBLUE (-1775 5525);
DISPLAY INVISIBLE (-1775 5525);
FORCEADD OFFPAGE..1
(-8075 4200);
FORCEPROP 2 LAST $XR0 43 
J 0
(-8296 4200);
DISPLAY 0.638298 (-8296 4200);
PAINT MONO (-8296 4200);
FORCEPROP 2 LAST CDS_LIB mstr_standard
J 0
(-8075 4200);
DISPLAY 0.808511 (-8075 4200);
DISPLAY INVISIBLE (-8075 4200);
FORCEPROP 1 LAST OFFPAGE TRUE
J 0
(-7750 4075);
DISPLAY 0.872340 (-7750 4075);
PAINT GREEN (-7750 4075);
DISPLAY INVISIBLE (-7750 4075);
FORCEPROP 1 LAST COMMENT_BODY TRUE
J 0
(-7950 4100);
DISPLAY 0.872340 (-7950 4100);
PAINT GREEN (-7950 4100);
DISPLAY INVISIBLE (-7950 4100);
FORCEPROP 2 LAST PATH I15
J 0
(-8325 4250);
DISPLAY 1.021277 (-8325 4250);
DISPLAY INVISIBLE (-8325 4250);
FORCEADD OFFPAGE..1
(-8075 4400);
FORCEPROP 2 LAST $XR0 43 
J 0
(-8296 4400);
DISPLAY 0.638298 (-8296 4400);
PAINT MONO (-8296 4400);
FORCEPROP 2 LAST CDS_LIB mstr_standard
J 0
(-8075 4400);
DISPLAY 0.723404 (-8075 4400);
PAINT MONO (-8075 4400);
DISPLAY INVISIBLE (-8075 4400);
FORCEPROP 1 LAST OFFPAGE TRUE
J 0
(-7750 4275);
DISPLAY 0.872340 (-7750 4275);
PAINT GREEN (-7750 4275);
DISPLAY INVISIBLE (-7750 4275);
FORCEPROP 1 LAST COMMENT_BODY TRUE
J 0
(-7950 4300);
DISPLAY 0.872340 (-7950 4300);
PAINT GREEN (-7950 4300);
DISPLAY INVISIBLE (-7950 4300);
FORCEPROP 2 LAST PATH I16
J 0
(-8325 4450);
DISPLAY 1.021277 (-8325 4450);
DISPLAY INVISIBLE (-8325 4450);
FORCEADD OFFPAGE..1
(-8075 4350);
FORCEPROP 2 LAST $XR0 43 
J 0
(-8296 4350);
DISPLAY 0.638298 (-8296 4350);
PAINT MONO (-8296 4350);
FORCEPROP 2 LAST CDS_LIB mstr_standard
J 0
(-8075 4350);
DISPLAY 0.808511 (-8075 4350);
DISPLAY INVISIBLE (-8075 4350);
FORCEPROP 1 LAST OFFPAGE TRUE
J 0
(-7750 4225);
DISPLAY 0.872340 (-7750 4225);
PAINT GREEN (-7750 4225);
DISPLAY INVISIBLE (-7750 4225);
FORCEPROP 1 LAST COMMENT_BODY TRUE
J 0
(-7950 4250);
DISPLAY 0.872340 (-7950 4250);
PAINT GREEN (-7950 4250);
DISPLAY INVISIBLE (-7950 4250);
FORCEPROP 2 LAST PATH I17
J 0
(-8325 4400);
DISPLAY 1.021277 (-8325 4400);
DISPLAY INVISIBLE (-8325 4400);
FORCEADD OFFPAGE..1
(-8075 4500);
FORCEPROP 2 LAST $XR0 43 
J 0
(-8296 4500);
DISPLAY 0.638298 (-8296 4500);
PAINT MONO (-8296 4500);
FORCEPROP 2 LAST CDS_LIB mstr_standard
J 0
(-8075 4500);
DISPLAY 0.808511 (-8075 4500);
DISPLAY INVISIBLE (-8075 4500);
FORCEPROP 1 LAST OFFPAGE TRUE
J 0
(-7750 4375);
DISPLAY 0.872340 (-7750 4375);
PAINT GREEN (-7750 4375);
DISPLAY INVISIBLE (-7750 4375);
FORCEPROP 1 LAST COMMENT_BODY TRUE
J 0
(-7950 4400);
DISPLAY 0.872340 (-7950 4400);
PAINT GREEN (-7950 4400);
DISPLAY INVISIBLE (-7950 4400);
FORCEPROP 2 LAST PATH I18
J 0
(-8325 4550);
DISPLAY 1.021277 (-8325 4550);
DISPLAY INVISIBLE (-8325 4550);
FORCEADD Q_CAP..1
R 2
(-8675 3200);
FORCEPROP 1 LAST LOCATION C160
J 2
(-8725 3300);
DISPLAY 0.489362 (-8725 3300);
PAINT SKYBLUE (-8725 3300);
FORCEPROP 0 LAST $SEC 1
J 0
(-8725 3350);
DISPLAY 0.680851 (-8725 3350);
PAINT MONO (-8725 3350);
DISPLAY INVISIBLE (-8725 3350);
FORCEPROP 0 LAST CDS_SEC 1
J 0
(-8725 3350);
DISPLAY 1.021277 (-8725 3350);
DISPLAY INVISIBLE (-8725 3350);
FORCEPROP 1 LASTPIN (-8675 3300) $PN 1
J 2
(-8685 3280);
DISPLAY 0.489362 (-8685 3280);
PAINT MONO (-8685 3280);
FORCEPROP 1 LASTPIN (-8675 3100) $PN 2
J 2
(-8685 3080);
DISPLAY 0.489362 (-8685 3080);
PAINT MONO (-8685 3080);
FORCEPROP 1 LAST PACK_TYPE 0402
J 2
(-8725 3000);
DISPLAY 0.489362 (-8725 3000);
PAINT SKYBLUE (-8725 3000);
FORCEPROP 1 LAST MATERIAL X7R
J 2
(-8725 3100);
DISPLAY 0.489362 (-8725 3100);
PAINT SKYBLUE (-8725 3100);
FORCEPROP 1 LAST TOLERANCE 10%
J 2
(-8725 3150);
DISPLAY 0.489362 (-8725 3150);
PAINT SKYBLUE (-8725 3150);
FORCEPROP 1 LAST VOLTAGE 25V
J 2
(-8725 3200);
DISPLAY 0.489362 (-8725 3200);
PAINT SKYBLUE (-8725 3200);
FORCEPROP 1 LAST VALUE 0.1UF
J 2
(-8725 3250);
DISPLAY 0.489362 (-8725 3250);
PAINT SKYBLUE (-8725 3250);
FORCEPROP 0 LAST BOM_COST MEM
J 2
(-8730 3345);
DISPLAY 0.595745 (-8730 3345);
PAINT MONO (-8730 3345);
DISPLAY INVISIBLE (-8730 3345);
FORCEPROP 2 LAST CDS_LIB pure_quanta
J 0
(-8675 3200);
DISPLAY INVISIBLE (-8675 3200);
FORCEPROP 2 LAST ROOM 
J 2
(-8730 3345);
DISPLAY 0.595745 (-8730 3345);
PAINT RED (-8730 3345);
DISPLAY INVISIBLE (-8730 3345);
FORCEPROP 1 LAST PATH I185
J 2
(-8725 3350);
DISPLAY 0.978723 (-8725 3350);
PAINT WHITE (-8725 3350);
DISPLAY INVISIBLE (-8725 3350);
FORCEPROP 1 LAST PART_NUMBER CH4104K1B00
J 2
(-8725 3050);
DISPLAY 0.489362 (-8725 3050);
PAINT SKYBLUE (-8725 3050);
DISPLAY INVISIBLE (-8725 3050);
FORCEADD GND..1
(-8675 2975);
FORCEPROP 3 LASTPIN (-8675 3025) SIG_NAME GND\g
J 0
(-8665 3035);
DISPLAY 0.659574 (-8665 3035);
PAINT MONO (-8665 3035);
DISPLAY INVISIBLE (-8665 3035);
FORCEPROP 2 LAST ROOM MEM_EFGH_DECOUPLING_CAPS
J 0
(-8650 3050);
DISPLAY 0.659574 (-8650 3050);
PAINT RED (-8650 3050);
DISPLAY INVISIBLE (-8650 3050);
FORCEPROP 1 LAST VOLTAGE 0
J 0
(-8695 3070);
DISPLAY 0.829787 (-8695 3070);
PAINT SKYBLUE (-8695 3070);
DISPLAY INVISIBLE (-8695 3070);
FORCEPROP 2 LAST CDS_LIB mstr_symbols
J 0
(-8675 2975);
DISPLAY 0.808511 (-8675 2975);
DISPLAY INVISIBLE (-8675 2975);
FORCEPROP 1 LAST SIZE 1B
J 0
(-8600 2925);
DISPLAY 0.723404 (-8600 2925);
PAINT GREEN (-8600 2925);
DISPLAY INVISIBLE (-8600 2925);
FORCEPROP 2 LAST BOM_COST MEM
J 0
(-8650 3100);
DISPLAY 0.659574 (-8650 3100);
DISPLAY INVISIBLE (-8650 3100);
FORCEPROP 1 LAST BODY_TYPE PLUMBING
J 0
(-8720 2932);
DISPLAY 0.276596 (-8720 2932);
PAINT GREEN (-8720 2932);
DISPLAY INVISIBLE (-8720 2932);
FORCEPROP 1 LAST HDL_POWER GND
J 0
(-8675 3125);
DISPLAY 0.723404 (-8675 3125);
PAINT GREEN (-8675 3125);
DISPLAY INVISIBLE (-8675 3125);
FORCEPROP 1 LAST PATH I186
J 0
(-8600 2975);
DISPLAY 0.872340 (-8600 2975);
PAINT AQUA (-8600 2975);
DISPLAY INVISIBLE (-8600 2975);
FORCEADD OFFPAGE..6
(-8950 2100);
FORCEPROP 2 LAST $XR5 109 
J 0
(-9260 1992);
DISPLAY 0.638298 (-9260 1992);
PAINT MONO (-9260 1992);
FORCEPROP 2 LAST $XR4 108 
J 0
(-9260 2172);
DISPLAY 0.638298 (-9260 2172);
PAINT MONO (-9260 2172);
FORCEPROP 2 LAST $XR3 107 
J 0
(-9260 2028);
DISPLAY 0.638298 (-9260 2028);
PAINT MONO (-9260 2028);
FORCEPROP 2 LAST $XR2 106 
J 0
(-9260 2136);
DISPLAY 0.638298 (-9260 2136);
PAINT MONO (-9260 2136);
FORCEPROP 2 LAST $XR1 105 
J 0
(-9260 2064);
DISPLAY 0.638298 (-9260 2064);
PAINT MONO (-9260 2064);
FORCEPROP 2 LAST $XR0 104 
J 0
(-9260 2100);
DISPLAY 0.638298 (-9260 2100);
PAINT MONO (-9260 2100);
FORCEPROP 2 LAST CDS_LIB mstr_standard
J 0
(-8950 2100);
DISPLAY INVISIBLE (-8950 2100);
FORCEPROP 1 LAST OFFPAGE TRUE
J 0
(-8625 1975);
DISPLAY 0.872340 (-8625 1975);
PAINT GREEN (-8625 1975);
DISPLAY INVISIBLE (-8625 1975);
FORCEPROP 1 LAST COMMENT_BODY TRUE
J 0
(-8850 2025);
DISPLAY 0.872340 (-8850 2025);
PAINT GREEN (-8850 2025);
DISPLAY INVISIBLE (-8850 2025);
FORCEPROP 2 LAST PATH I187
J 0
(-8900 2175);
DISPLAY 1.021277 (-8900 2175);
DISPLAY INVISIBLE (-8900 2175);
FORCEADD Q_RES..1
R 2
(-8400 2100);
FORCEPROP 1 LAST LOCATION R1184
J 2
(-8350 2150);
DISPLAY 0.489362 (-8350 2150);
PAINT SKYBLUE (-8350 2150);
FORCEPROP 0 LAST $SEC 1
J 0
(-8350 2200);
DISPLAY 0.680851 (-8350 2200);
PAINT MONO (-8350 2200);
DISPLAY INVISIBLE (-8350 2200);
FORCEPROP 0 LAST CDS_SEC 1
J 0
(-8350 2200);
DISPLAY 1.021277 (-8350 2200);
DISPLAY INVISIBLE (-8350 2200);
FORCEPROP 1 LASTPIN (-8300 2100) $PN 1
J 2
(-8312 2112);
DISPLAY 0.489362 (-8312 2112);
PAINT MONO (-8312 2112);
FORCEPROP 1 LASTPIN (-8500 2100) $PN 2
J 2
(-8462 2112);
DISPLAY 0.489362 (-8462 2112);
PAINT MONO (-8462 2112);
FORCEPROP 1 LAST VALUE 1K
J 0
(-8400 2050);
DISPLAY 0.489362 (-8400 2050);
PAINT SKYBLUE (-8400 2050);
FORCEPROP 1 LAST PACK_TYPE 0402LF
J 0
(-8575 2025);
DISPLAY 0.489362 (-8575 2025);
PAINT SKYBLUE (-8575 2025);
DISPLAY INVISIBLE (-8575 2025);
FORCEPROP 1 LAST MATERIAL CHIP
J 0
(-8575 2075);
DISPLAY 0.489362 (-8575 2075);
PAINT SKYBLUE (-8575 2075);
DISPLAY INVISIBLE (-8575 2075);
FORCEPROP 1 LAST WATTAGE 1/16W
J 0
(-8325 2025);
DISPLAY 0.489362 (-8325 2025);
PAINT SKYBLUE (-8325 2025);
DISPLAY INVISIBLE (-8325 2025);
FORCEPROP 2 LAST BOM_COST MEM
J 0
(-8425 2250);
DISPLAY 0.744681 (-8425 2250);
PAINT WHITE (-8425 2250);
DISPLAY INVISIBLE (-8425 2250);
FORCEPROP 2 LAST CDS_LIB pure_quanta
J 0
(-8400 2100);
DISPLAY INVISIBLE (-8400 2100);
FORCEPROP 1 LAST TOLERANCE 1%
J 2
(-8275 2075);
DISPLAY 0.489362 (-8275 2075);
PAINT SKYBLUE (-8275 2075);
DISPLAY INVISIBLE (-8275 2075);
FORCEPROP 2 LAST ROOM 
J 0
(-8425 2200);
DISPLAY 0.744681 (-8425 2200);
PAINT RED (-8425 2200);
DISPLAY INVISIBLE (-8425 2200);
FORCEPROP 1 LAST PATH I188
J 2
(-8350 2250);
DISPLAY 0.978723 (-8350 2250);
PAINT WHITE (-8350 2250);
DISPLAY INVISIBLE (-8350 2250);
FORCEPROP 1 LAST PART_NUMBER CS21002FB06
J 0
(-8500 2150);
DISPLAY 0.489362 (-8500 2150);
PAINT SKYBLUE (-8500 2150);
DISPLAY INVISIBLE (-8500 2150);
FORCEADD Q_RES..2
R 2
(-8525 2250);
FORCEPROP 1 LAST LOCATION R109
J 2
(-8570 2375);
DISPLAY 0.489362 (-8570 2375);
PAINT SKYBLUE (-8570 2375);
FORCEPROP 0 LAST $SEC 1
J 0
(-8550 2425);
DISPLAY 0.680851 (-8550 2425);
PAINT MONO (-8550 2425);
DISPLAY INVISIBLE (-8550 2425);
FORCEPROP 0 LAST CDS_SEC 1
J 0
(-8550 2425);
DISPLAY 1.021277 (-8550 2425);
DISPLAY INVISIBLE (-8550 2425);
FORCEPROP 1 LASTPIN (-8525 2350) $PN 1
J 2
(-8530 2312);
DISPLAY 0.489362 (-8530 2312);
PAINT MONO (-8530 2312);
FORCEPROP 1 LASTPIN (-8525 2150) $PN 2
J 2
(-8530 2160);
DISPLAY 0.489362 (-8530 2160);
PAINT MONO (-8530 2160);
FORCEPROP 1 LAST PACK_TYPE 0402LF
J 2
(-8575 2200);
DISPLAY 0.489362 (-8575 2200);
PAINT SKYBLUE (-8575 2200);
FORCEPROP 1 LAST VALUE 1K
J 2
(-8570 2325);
DISPLAY 0.489362 (-8570 2325);
PAINT SKYBLUE (-8570 2325);
FORCEPROP 1 LAST TOLERANCE 1%
J 2
(-8575 2300);
DISPLAY 0.489362 (-8575 2300);
PAINT SKYBLUE (-8575 2300);
FORCEPROP 1 LAST WATTAGE 1/16W
J 2
(-8575 2275);
DISPLAY 0.489362 (-8575 2275);
PAINT SKYBLUE (-8575 2275);
FORCEPROP 1 LAST MATERIAL EMPTY
J 2
(-8575 2250);
DISPLAY 0.489362 (-8575 2250);
PAINT RED (-8575 2250);
FORCEPROP 2 LAST CDS_LIB pure_quanta
J 2
(-8525 2250);
DISPLAY INVISIBLE (-8525 2250);
FORCEPROP 2 LAST BOM_COST MEM
J 2
(-8575 2425);
DISPLAY 0.808511 (-8575 2425);
DISPLAY INVISIBLE (-8575 2425);
FORCEPROP 2 LAST ROOM 
J 2
(-8575 2475);
DISPLAY 0.808511 (-8575 2475);
PAINT RED (-8575 2475);
DISPLAY INVISIBLE (-8575 2475);
FORCEPROP 1 LAST PATH I189
J 2
(-8575 2425);
DISPLAY 0.978723 (-8575 2425);
PAINT WHITE (-8575 2425);
DISPLAY INVISIBLE (-8575 2425);
FORCEPROP 1 LAST PART_NUMBER CS21002FB06
J 2
(-8575 2225);
DISPLAY 0.489362 (-8575 2225);
PAINT SKYBLUE (-8575 2225);
DISPLAY INVISIBLE (-8575 2225);
FORCEADD OFFPAGE..1
(-8075 4550);
FORCEPROP 2 LAST $XR0 43 
J 0
(-8296 4550);
DISPLAY 0.638298 (-8296 4550);
PAINT MONO (-8296 4550);
FORCEPROP 2 LAST CDS_LIB mstr_standard
J 0
(-8075 4550);
DISPLAY 0.723404 (-8075 4550);
PAINT MONO (-8075 4550);
DISPLAY INVISIBLE (-8075 4550);
FORCEPROP 1 LAST OFFPAGE TRUE
J 0
(-7750 4425);
DISPLAY 0.872340 (-7750 4425);
PAINT GREEN (-7750 4425);
DISPLAY INVISIBLE (-7750 4425);
FORCEPROP 1 LAST COMMENT_BODY TRUE
J 0
(-7950 4450);
DISPLAY 0.872340 (-7950 4450);
PAINT GREEN (-7950 4450);
DISPLAY INVISIBLE (-7950 4450);
FORCEPROP 2 LAST PATH I19
J 0
(-8325 4600);
DISPLAY 1.021277 (-8325 4600);
DISPLAY INVISIBLE (-8325 4600);
FORCEADD VCC_CORE..1
(-8525 2425);
FORCEPROP 3 LASTPIN (-8525 2375) SIG_NAME P3V3\g
J 0
(-8515 2385);
DISPLAY 0.659574 (-8515 2385);
PAINT MONO (-8515 2385);
DISPLAY INVISIBLE (-8515 2385);
FORCEPROP 1 LAST HDL_POWER P3V3
J 1
(-8525 2475);
DISPLAY 0.489362 (-8525 2475);
PAINT GREEN (-8525 2475);
FORCEPROP 2 LAST ROOM PVCCINFAON_CPU0_CTRL
J 0
(-8525 2525);
DISPLAY 0.808511 (-8525 2525);
PAINT RED (-8525 2525);
DISPLAY INVISIBLE (-8525 2525);
FORCEPROP 0 LAST VOLTAGE 3.3
J 0
(-8800 2575);
DISPLAY 1.021277 (-8800 2575);
PAINT SKYBLUE (-8800 2575);
DISPLAY INVISIBLE (-8800 2575);
FORCEPROP 2 LAST CDS_LIB mstr_symbols
J 0
(-8525 2425);
DISPLAY INVISIBLE (-8525 2425);
FORCEPROP 1 LAST PATH I190
J 0
(-8475 2450);
DISPLAY 0.872340 (-8475 2450);
PAINT AQUA (-8475 2450);
DISPLAY INVISIBLE (-8475 2450);
FORCEADD VCC_CORE..1
(-8275 2425);
FORCEPROP 3 LASTPIN (-8275 2375) SIG_NAME P3V3\g
J 0
(-8265 2385);
DISPLAY 0.659574 (-8265 2385);
PAINT MONO (-8265 2385);
DISPLAY INVISIBLE (-8265 2385);
FORCEPROP 1 LAST HDL_POWER P3V3
J 1
(-8275 2475);
DISPLAY 0.489362 (-8275 2475);
PAINT GREEN (-8275 2475);
FORCEPROP 2 LAST ROOM PVCCINFAON_CPU0_CTRL
J 0
(-8275 2525);
DISPLAY 0.808511 (-8275 2525);
PAINT RED (-8275 2525);
DISPLAY INVISIBLE (-8275 2525);
FORCEPROP 0 LAST VOLTAGE 3.3
J 0
(-8550 2575);
DISPLAY 1.021277 (-8550 2575);
PAINT SKYBLUE (-8550 2575);
DISPLAY INVISIBLE (-8550 2575);
FORCEPROP 2 LAST CDS_LIB mstr_symbols
J 0
(-8275 2425);
DISPLAY INVISIBLE (-8275 2425);
FORCEPROP 1 LAST PATH I191
J 0
(-8225 2450);
DISPLAY 0.872340 (-8225 2450);
PAINT AQUA (-8225 2450);
DISPLAY INVISIBLE (-8225 2450);
FORCEADD Q_RES..2
(-8275 2250);
FORCEPROP 1 LAST LOCATION R110
J 0
(-8230 2375);
DISPLAY 0.489362 (-8230 2375);
PAINT SKYBLUE (-8230 2375);
FORCEPROP 0 LAST $SEC 1
J 0
(-8225 2425);
DISPLAY 0.680851 (-8225 2425);
PAINT MONO (-8225 2425);
DISPLAY INVISIBLE (-8225 2425);
FORCEPROP 0 LAST CDS_SEC 1
J 0
(-8225 2425);
DISPLAY 1.021277 (-8225 2425);
DISPLAY INVISIBLE (-8225 2425);
FORCEPROP 1 LASTPIN (-8275 2350) $PN 1
J 0
(-8270 2312);
DISPLAY 0.489362 (-8270 2312);
PAINT MONO (-8270 2312);
FORCEPROP 1 LASTPIN (-8275 2150) $PN 2
J 0
(-8270 2160);
DISPLAY 0.489362 (-8270 2160);
PAINT MONO (-8270 2160);
FORCEPROP 1 LAST VALUE 1K
J 0
(-8230 2325);
DISPLAY 0.489362 (-8230 2325);
PAINT SKYBLUE (-8230 2325);
FORCEPROP 1 LAST WATTAGE 1/16W
J 0
(-8225 2275);
DISPLAY 0.489362 (-8225 2275);
PAINT SKYBLUE (-8225 2275);
FORCEPROP 1 LAST MATERIAL EMPTY
J 0
(-8225 2250);
DISPLAY 0.489362 (-8225 2250);
PAINT RED (-8225 2250);
FORCEPROP 1 LAST PACK_TYPE 0402LF
J 0
(-8225 2200);
DISPLAY 0.489362 (-8225 2200);
PAINT SKYBLUE (-8225 2200);
FORCEPROP 1 LAST TOLERANCE 1%
J 0
(-8225 2300);
DISPLAY 0.489362 (-8225 2300);
PAINT SKYBLUE (-8225 2300);
FORCEPROP 2 LAST BOM_COST MEM
J 0
(-8225 2425);
DISPLAY 0.808511 (-8225 2425);
DISPLAY INVISIBLE (-8225 2425);
FORCEPROP 2 LAST CDS_LIB pure_quanta
J 0
(-8275 2250);
DISPLAY INVISIBLE (-8275 2250);
FORCEPROP 2 LAST ROOM 
J 0
(-8225 2475);
DISPLAY 0.808511 (-8225 2475);
PAINT RED (-8225 2475);
DISPLAY INVISIBLE (-8225 2475);
FORCEPROP 1 LAST PATH I192
J 0
(-8225 2425);
DISPLAY 0.978723 (-8225 2425);
PAINT WHITE (-8225 2425);
DISPLAY INVISIBLE (-8225 2425);
FORCEPROP 1 LAST PART_NUMBER CS21002FB06
J 0
(-8225 2225);
DISPLAY 0.489362 (-8225 2225);
PAINT SKYBLUE (-8225 2225);
DISPLAY INVISIBLE (-8225 2225);
FORCEADD OFFPAGE..2
(-2450 4425);
FORCEPROP 2 LAST $XR0 43 
J 0
(-2261 4425);
DISPLAY 0.638298 (-2261 4425);
PAINT MONO (-2261 4425);
FORCEPROP 2 LAST CDS_LIB mstr_standard
J 0
(-2450 4425);
DISPLAY 0.723404 (-2450 4425);
PAINT MONO (-2450 4425);
DISPLAY INVISIBLE (-2450 4425);
FORCEPROP 1 LAST OFFPAGE TRUE
J 0
(-2125 4300);
DISPLAY 0.723404 (-2125 4300);
PAINT GREEN (-2125 4300);
DISPLAY INVISIBLE (-2125 4300);
FORCEPROP 1 LAST COMMENT_BODY TRUE
J 0
(-2495 4330);
DISPLAY 0.872340 (-2495 4330);
PAINT GREEN (-2495 4330);
DISPLAY INVISIBLE (-2495 4330);
FORCEPROP 2 LAST PATH I194
J 0
(-2250 4475);
DISPLAY 0.680851 (-2250 4475);
DISPLAY INVISIBLE (-2250 4475);
FORCEADD OFFPAGE..2
(-2450 4475);
FORCEPROP 2 LAST $XR0 43 
J 0
(-2261 4475);
DISPLAY 0.638298 (-2261 4475);
PAINT MONO (-2261 4475);
FORCEPROP 2 LAST CDS_LIB mstr_standard
J 0
(-2450 4475);
DISPLAY 0.723404 (-2450 4475);
PAINT MONO (-2450 4475);
DISPLAY INVISIBLE (-2450 4475);
FORCEPROP 1 LAST OFFPAGE TRUE
J 0
(-2125 4350);
DISPLAY 0.723404 (-2125 4350);
PAINT GREEN (-2125 4350);
DISPLAY INVISIBLE (-2125 4350);
FORCEPROP 1 LAST COMMENT_BODY TRUE
J 0
(-2495 4380);
DISPLAY 0.872340 (-2495 4380);
PAINT GREEN (-2495 4380);
DISPLAY INVISIBLE (-2495 4380);
FORCEPROP 2 LAST PATH I195
J 0
(-2250 4525);
DISPLAY 0.680851 (-2250 4525);
DISPLAY INVISIBLE (-2250 4525);
FORCEADD OFFPAGE..2
(-2450 3375);
FORCEPROP 2 LAST $XR0 43 
J 0
(-2261 3375);
DISPLAY 0.638298 (-2261 3375);
PAINT MONO (-2261 3375);
FORCEPROP 2 LAST CDS_LIB mstr_standard
J 0
(-2450 3375);
DISPLAY 0.723404 (-2450 3375);
PAINT MONO (-2450 3375);
DISPLAY INVISIBLE (-2450 3375);
FORCEPROP 1 LAST OFFPAGE TRUE
J 0
(-2125 3250);
DISPLAY 0.723404 (-2125 3250);
PAINT GREEN (-2125 3250);
DISPLAY INVISIBLE (-2125 3250);
FORCEPROP 1 LAST COMMENT_BODY TRUE
J 0
(-2495 3280);
DISPLAY 0.872340 (-2495 3280);
PAINT GREEN (-2495 3280);
DISPLAY INVISIBLE (-2495 3280);
FORCEPROP 2 LAST PATH I196
J 0
(-2250 3425);
DISPLAY 0.680851 (-2250 3425);
DISPLAY INVISIBLE (-2250 3425);
FORCEADD OFFPAGE..2
(-2450 3425);
FORCEPROP 2 LAST $XR0 43 
J 0
(-2261 3425);
DISPLAY 0.638298 (-2261 3425);
PAINT MONO (-2261 3425);
FORCEPROP 2 LAST CDS_LIB mstr_standard
J 0
(-2450 3425);
DISPLAY 0.723404 (-2450 3425);
PAINT MONO (-2450 3425);
DISPLAY INVISIBLE (-2450 3425);
FORCEPROP 1 LAST OFFPAGE TRUE
J 0
(-2125 3300);
DISPLAY 0.723404 (-2125 3300);
PAINT GREEN (-2125 3300);
DISPLAY INVISIBLE (-2125 3300);
FORCEPROP 1 LAST COMMENT_BODY TRUE
J 0
(-2495 3330);
DISPLAY 0.872340 (-2495 3330);
PAINT GREEN (-2495 3330);
DISPLAY INVISIBLE (-2495 3330);
FORCEPROP 2 LAST PATH I197
J 0
(-2250 3475);
DISPLAY 0.680851 (-2250 3475);
DISPLAY INVISIBLE (-2250 3475);
FORCEADD TAP..1
(-3050 4375);
FORCEPROP 3 LASTPIN (-3100 4375) SIG_NAME M_G_CPU1_SA_DQS_DN<9>
J 0
(-3090 4385);
DISPLAY 0.659574 (-3090 4385);
PAINT MONO (-3090 4385);
DISPLAY INVISIBLE (-3090 4385);
FORCEPROP 1 LASTPIN (-3100 4375) BN 9
J 0
(-3112 4383);
DISPLAY 0.489362 (-3112 4383);
PAINT GREEN (-3112 4383);
FORCEPROP 2 LAST CDS_LIB mstr_standard
J 0
(-3050 4375);
DISPLAY 0.723404 (-3050 4375);
PAINT MONO (-3050 4375);
DISPLAY INVISIBLE (-3050 4375);
FORCEPROP 1 LAST BODY_TYPE PLUMBING
J 0
(-3050 4425);
DISPLAY 0.872340 (-3050 4425);
PAINT GREEN (-3050 4425);
DISPLAY INVISIBLE (-3050 4425);
FORCEPROP 1 LAST HDL_TAP TRUE
J 0
(-2725 4250);
DISPLAY 0.872340 (-2725 4250);
DISPLAY INVISIBLE (-2725 4250);
FORCEPROP 1 LAST PATH I198
J 0
(-3052 4375);
DISPLAY 0.872340 (-3052 4375);
PAINT GREEN (-3052 4375);
DISPLAY INVISIBLE (-3052 4375);
FORCEADD TAP..1
(-3050 4275);
FORCEPROP 3 LASTPIN (-3100 4275) SIG_NAME M_G_CPU1_SA_DQS_DN<8>
J 0
(-3090 4285);
DISPLAY 0.659574 (-3090 4285);
PAINT MONO (-3090 4285);
DISPLAY INVISIBLE (-3090 4285);
FORCEPROP 1 LASTPIN (-3100 4275) BN 8
J 0
(-3112 4283);
DISPLAY 0.489362 (-3112 4283);
PAINT GREEN (-3112 4283);
FORCEPROP 2 LAST CDS_LIB mstr_standard
J 0
(-3050 4275);
DISPLAY 0.723404 (-3050 4275);
PAINT MONO (-3050 4275);
DISPLAY INVISIBLE (-3050 4275);
FORCEPROP 1 LAST BODY_TYPE PLUMBING
J 0
(-3050 4325);
DISPLAY 0.872340 (-3050 4325);
PAINT GREEN (-3050 4325);
DISPLAY INVISIBLE (-3050 4325);
FORCEPROP 1 LAST HDL_TAP TRUE
J 0
(-2725 4150);
DISPLAY 0.872340 (-2725 4150);
DISPLAY INVISIBLE (-2725 4150);
FORCEPROP 1 LAST PATH I199
J 0
(-3052 4275);
DISPLAY 0.872340 (-3052 4275);
PAINT GREEN (-3052 4275);
DISPLAY INVISIBLE (-3052 4275);
FORCEADD OFFPAGE..5
(-8075 1900);
FORCEPROP 2 LAST $XR0 43 
J 0
(-8329 1900);
DISPLAY 0.638298 (-8329 1900);
PAINT MONO (-8329 1900);
FORCEPROP 2 LAST CDS_LIB mstr_standard
J 0
(-8075 1900);
DISPLAY 0.808511 (-8075 1900);
DISPLAY INVISIBLE (-8075 1900);
FORCEPROP 1 LAST OFFPAGE TRUE
J 0
(-7750 1775);
DISPLAY 0.872340 (-7750 1775);
PAINT GREEN (-7750 1775);
DISPLAY INVISIBLE (-7750 1775);
FORCEPROP 1 LAST COMMENT_BODY TRUE
J 0
(-7975 1825);
DISPLAY 0.872340 (-7975 1825);
PAINT GREEN (-7975 1825);
DISPLAY INVISIBLE (-7975 1825);
FORCEPROP 2 LAST PATH I2
J 0
(-8325 1950);
DISPLAY 1.021277 (-8325 1950);
DISPLAY INVISIBLE (-8325 1950);
FORCEADD OFFPAGE..1
(-8075 5000);
FORCEPROP 2 LAST $XR0 43 
J 0
(-8296 5000);
DISPLAY 0.638298 (-8296 5000);
PAINT MONO (-8296 5000);
FORCEPROP 2 LAST CDS_LIB mstr_standard
J 0
(-8075 5000);
DISPLAY 0.723404 (-8075 5000);
PAINT MONO (-8075 5000);
DISPLAY INVISIBLE (-8075 5000);
FORCEPROP 1 LAST OFFPAGE TRUE
J 0
(-7750 4875);
DISPLAY 0.872340 (-7750 4875);
PAINT GREEN (-7750 4875);
DISPLAY INVISIBLE (-7750 4875);
FORCEPROP 1 LAST COMMENT_BODY TRUE
J 0
(-7950 4900);
DISPLAY 0.872340 (-7950 4900);
PAINT GREEN (-7950 4900);
DISPLAY INVISIBLE (-7950 4900);
FORCEPROP 2 LAST PATH I20
J 0
(-8325 5050);
DISPLAY 1.021277 (-8325 5050);
DISPLAY INVISIBLE (-8325 5050);
FORCEADD TAP..1
(-3250 4425);
FORCEPROP 3 LASTPIN (-3300 4425) SIG_NAME M_G_CPU1_SA_DQS_DP<9>
J 0
(-3290 4435);
DISPLAY 0.659574 (-3290 4435);
PAINT MONO (-3290 4435);
DISPLAY INVISIBLE (-3290 4435);
FORCEPROP 1 LASTPIN (-3300 4425) BN 9
J 0
(-3312 4433);
DISPLAY 0.489362 (-3312 4433);
PAINT GREEN (-3312 4433);
FORCEPROP 2 LAST CDS_LIB mstr_standard
J 0
(-3250 4425);
DISPLAY 0.723404 (-3250 4425);
PAINT MONO (-3250 4425);
DISPLAY INVISIBLE (-3250 4425);
FORCEPROP 1 LAST BODY_TYPE PLUMBING
J 0
(-3250 4475);
DISPLAY 0.872340 (-3250 4475);
PAINT GREEN (-3250 4475);
DISPLAY INVISIBLE (-3250 4475);
FORCEPROP 1 LAST HDL_TAP TRUE
J 0
(-2925 4300);
DISPLAY 0.872340 (-2925 4300);
DISPLAY INVISIBLE (-2925 4300);
FORCEPROP 1 LAST PATH I200
J 0
(-3252 4425);
DISPLAY 0.872340 (-3252 4425);
PAINT GREEN (-3252 4425);
DISPLAY INVISIBLE (-3252 4425);
FORCEADD TAP..1
(-3250 4325);
FORCEPROP 3 LASTPIN (-3300 4325) SIG_NAME M_G_CPU1_SA_DQS_DP<8>
J 0
(-3290 4335);
DISPLAY 0.659574 (-3290 4335);
PAINT MONO (-3290 4335);
DISPLAY INVISIBLE (-3290 4335);
FORCEPROP 1 LASTPIN (-3300 4325) BN 8
J 0
(-3312 4333);
DISPLAY 0.489362 (-3312 4333);
PAINT GREEN (-3312 4333);
FORCEPROP 2 LAST CDS_LIB mstr_standard
J 0
(-3250 4325);
DISPLAY 0.723404 (-3250 4325);
PAINT MONO (-3250 4325);
DISPLAY INVISIBLE (-3250 4325);
FORCEPROP 1 LAST BODY_TYPE PLUMBING
J 0
(-3250 4375);
DISPLAY 0.872340 (-3250 4375);
PAINT GREEN (-3250 4375);
DISPLAY INVISIBLE (-3250 4375);
FORCEPROP 1 LAST HDL_TAP TRUE
J 0
(-2925 4200);
DISPLAY 0.872340 (-2925 4200);
DISPLAY INVISIBLE (-2925 4200);
FORCEPROP 1 LAST PATH I201
J 0
(-3252 4325);
DISPLAY 0.872340 (-3252 4325);
PAINT GREEN (-3252 4325);
DISPLAY INVISIBLE (-3252 4325);
FORCEADD TAP..1
(-3050 4175);
FORCEPROP 3 LASTPIN (-3100 4175) SIG_NAME M_G_CPU1_SA_DQS_DN<7>
J 0
(-3090 4185);
DISPLAY 0.659574 (-3090 4185);
PAINT MONO (-3090 4185);
DISPLAY INVISIBLE (-3090 4185);
FORCEPROP 1 LASTPIN (-3100 4175) BN 7
J 0
(-3112 4183);
DISPLAY 0.489362 (-3112 4183);
PAINT GREEN (-3112 4183);
FORCEPROP 2 LAST CDS_LIB mstr_standard
J 0
(-3050 4175);
DISPLAY 0.723404 (-3050 4175);
PAINT MONO (-3050 4175);
DISPLAY INVISIBLE (-3050 4175);
FORCEPROP 1 LAST BODY_TYPE PLUMBING
J 0
(-3050 4225);
DISPLAY 0.872340 (-3050 4225);
PAINT GREEN (-3050 4225);
DISPLAY INVISIBLE (-3050 4225);
FORCEPROP 1 LAST HDL_TAP TRUE
J 0
(-2725 4050);
DISPLAY 0.872340 (-2725 4050);
DISPLAY INVISIBLE (-2725 4050);
FORCEPROP 1 LAST PATH I202
J 0
(-3052 4175);
DISPLAY 0.872340 (-3052 4175);
PAINT GREEN (-3052 4175);
DISPLAY INVISIBLE (-3052 4175);
FORCEADD TAP..1
(-3050 4075);
FORCEPROP 3 LASTPIN (-3100 4075) SIG_NAME M_G_CPU1_SA_DQS_DN<6>
J 0
(-3090 4085);
DISPLAY 0.659574 (-3090 4085);
PAINT MONO (-3090 4085);
DISPLAY INVISIBLE (-3090 4085);
FORCEPROP 1 LASTPIN (-3100 4075) BN 6
J 0
(-3112 4083);
DISPLAY 0.489362 (-3112 4083);
PAINT GREEN (-3112 4083);
FORCEPROP 2 LAST CDS_LIB mstr_standard
J 0
(-3050 4075);
DISPLAY 0.723404 (-3050 4075);
PAINT MONO (-3050 4075);
DISPLAY INVISIBLE (-3050 4075);
FORCEPROP 1 LAST BODY_TYPE PLUMBING
J 0
(-3050 4125);
DISPLAY 0.872340 (-3050 4125);
PAINT GREEN (-3050 4125);
DISPLAY INVISIBLE (-3050 4125);
FORCEPROP 1 LAST HDL_TAP TRUE
J 0
(-2725 3950);
DISPLAY 0.872340 (-2725 3950);
DISPLAY INVISIBLE (-2725 3950);
FORCEPROP 1 LAST PATH I203
J 0
(-3052 4075);
DISPLAY 0.872340 (-3052 4075);
PAINT GREEN (-3052 4075);
DISPLAY INVISIBLE (-3052 4075);
FORCEADD TAP..1
(-3050 3875);
FORCEPROP 3 LASTPIN (-3100 3875) SIG_NAME M_G_CPU1_SA_DQS_DN<4>
J 0
(-3090 3885);
DISPLAY 0.659574 (-3090 3885);
PAINT MONO (-3090 3885);
DISPLAY INVISIBLE (-3090 3885);
FORCEPROP 1 LASTPIN (-3100 3875) BN 4
J 0
(-3112 3883);
DISPLAY 0.489362 (-3112 3883);
PAINT GREEN (-3112 3883);
FORCEPROP 2 LAST CDS_LIB mstr_standard
J 0
(-3050 3875);
DISPLAY 0.723404 (-3050 3875);
PAINT MONO (-3050 3875);
DISPLAY INVISIBLE (-3050 3875);
FORCEPROP 1 LAST BODY_TYPE PLUMBING
J 0
(-3050 3925);
DISPLAY 0.872340 (-3050 3925);
PAINT GREEN (-3050 3925);
DISPLAY INVISIBLE (-3050 3925);
FORCEPROP 1 LAST HDL_TAP TRUE
J 0
(-2725 3750);
DISPLAY 0.872340 (-2725 3750);
DISPLAY INVISIBLE (-2725 3750);
FORCEPROP 1 LAST PATH I204
J 0
(-3052 3875);
DISPLAY 0.872340 (-3052 3875);
PAINT GREEN (-3052 3875);
DISPLAY INVISIBLE (-3052 3875);
FORCEADD TAP..1
(-3050 3975);
FORCEPROP 3 LASTPIN (-3100 3975) SIG_NAME M_G_CPU1_SA_DQS_DN<5>
J 0
(-3090 3985);
DISPLAY 0.659574 (-3090 3985);
PAINT MONO (-3090 3985);
DISPLAY INVISIBLE (-3090 3985);
FORCEPROP 1 LASTPIN (-3100 3975) BN 5
J 0
(-3112 3983);
DISPLAY 0.489362 (-3112 3983);
PAINT GREEN (-3112 3983);
FORCEPROP 2 LAST CDS_LIB mstr_standard
J 0
(-3050 3975);
DISPLAY 0.723404 (-3050 3975);
PAINT MONO (-3050 3975);
DISPLAY INVISIBLE (-3050 3975);
FORCEPROP 1 LAST BODY_TYPE PLUMBING
J 0
(-3050 4025);
DISPLAY 0.872340 (-3050 4025);
PAINT GREEN (-3050 4025);
DISPLAY INVISIBLE (-3050 4025);
FORCEPROP 1 LAST HDL_TAP TRUE
J 0
(-2725 3850);
DISPLAY 0.872340 (-2725 3850);
DISPLAY INVISIBLE (-2725 3850);
FORCEPROP 1 LAST PATH I205
J 0
(-3052 3975);
DISPLAY 0.872340 (-3052 3975);
PAINT GREEN (-3052 3975);
DISPLAY INVISIBLE (-3052 3975);
FORCEADD TAP..1
(-3050 3775);
FORCEPROP 3 LASTPIN (-3100 3775) SIG_NAME M_G_CPU1_SA_DQS_DN<3>
J 0
(-3090 3785);
DISPLAY 0.659574 (-3090 3785);
PAINT MONO (-3090 3785);
DISPLAY INVISIBLE (-3090 3785);
FORCEPROP 1 LASTPIN (-3100 3775) BN 3
J 0
(-3112 3783);
DISPLAY 0.489362 (-3112 3783);
PAINT GREEN (-3112 3783);
FORCEPROP 2 LAST CDS_LIB mstr_standard
J 0
(-3050 3775);
DISPLAY 0.723404 (-3050 3775);
PAINT MONO (-3050 3775);
DISPLAY INVISIBLE (-3050 3775);
FORCEPROP 1 LAST BODY_TYPE PLUMBING
J 0
(-3050 3825);
DISPLAY 0.872340 (-3050 3825);
PAINT GREEN (-3050 3825);
DISPLAY INVISIBLE (-3050 3825);
FORCEPROP 1 LAST HDL_TAP TRUE
J 0
(-2725 3650);
DISPLAY 0.872340 (-2725 3650);
DISPLAY INVISIBLE (-2725 3650);
FORCEPROP 1 LAST PATH I206
J 0
(-3052 3775);
DISPLAY 0.872340 (-3052 3775);
PAINT GREEN (-3052 3775);
DISPLAY INVISIBLE (-3052 3775);
FORCEADD TAP..1
(-3250 4225);
FORCEPROP 3 LASTPIN (-3300 4225) SIG_NAME M_G_CPU1_SA_DQS_DP<7>
J 0
(-3290 4235);
DISPLAY 0.659574 (-3290 4235);
PAINT MONO (-3290 4235);
DISPLAY INVISIBLE (-3290 4235);
FORCEPROP 1 LASTPIN (-3300 4225) BN 7
J 0
(-3312 4233);
DISPLAY 0.489362 (-3312 4233);
PAINT GREEN (-3312 4233);
FORCEPROP 2 LAST CDS_LIB mstr_standard
J 0
(-3250 4225);
DISPLAY 0.723404 (-3250 4225);
PAINT MONO (-3250 4225);
DISPLAY INVISIBLE (-3250 4225);
FORCEPROP 1 LAST BODY_TYPE PLUMBING
J 0
(-3250 4275);
DISPLAY 0.872340 (-3250 4275);
PAINT GREEN (-3250 4275);
DISPLAY INVISIBLE (-3250 4275);
FORCEPROP 1 LAST HDL_TAP TRUE
J 0
(-2925 4100);
DISPLAY 0.872340 (-2925 4100);
DISPLAY INVISIBLE (-2925 4100);
FORCEPROP 1 LAST PATH I207
J 0
(-3252 4225);
DISPLAY 0.872340 (-3252 4225);
PAINT GREEN (-3252 4225);
DISPLAY INVISIBLE (-3252 4225);
FORCEADD TAP..1
(-3250 4125);
FORCEPROP 3 LASTPIN (-3300 4125) SIG_NAME M_G_CPU1_SA_DQS_DP<6>
J 0
(-3290 4135);
DISPLAY 0.659574 (-3290 4135);
PAINT MONO (-3290 4135);
DISPLAY INVISIBLE (-3290 4135);
FORCEPROP 1 LASTPIN (-3300 4125) BN 6
J 0
(-3312 4133);
DISPLAY 0.489362 (-3312 4133);
PAINT GREEN (-3312 4133);
FORCEPROP 2 LAST CDS_LIB mstr_standard
J 0
(-3250 4125);
DISPLAY 0.723404 (-3250 4125);
PAINT MONO (-3250 4125);
DISPLAY INVISIBLE (-3250 4125);
FORCEPROP 1 LAST BODY_TYPE PLUMBING
J 0
(-3250 4175);
DISPLAY 0.872340 (-3250 4175);
PAINT GREEN (-3250 4175);
DISPLAY INVISIBLE (-3250 4175);
FORCEPROP 1 LAST HDL_TAP TRUE
J 0
(-2925 4000);
DISPLAY 0.872340 (-2925 4000);
DISPLAY INVISIBLE (-2925 4000);
FORCEPROP 1 LAST PATH I208
J 0
(-3252 4125);
DISPLAY 0.872340 (-3252 4125);
PAINT GREEN (-3252 4125);
DISPLAY INVISIBLE (-3252 4125);
FORCEADD TAP..1
(-3250 4025);
FORCEPROP 3 LASTPIN (-3300 4025) SIG_NAME M_G_CPU1_SA_DQS_DP<5>
J 0
(-3290 4035);
DISPLAY 0.659574 (-3290 4035);
PAINT MONO (-3290 4035);
DISPLAY INVISIBLE (-3290 4035);
FORCEPROP 1 LASTPIN (-3300 4025) BN 5
J 0
(-3312 4033);
DISPLAY 0.489362 (-3312 4033);
PAINT GREEN (-3312 4033);
FORCEPROP 2 LAST CDS_LIB mstr_standard
J 0
(-3250 4025);
DISPLAY 0.723404 (-3250 4025);
PAINT MONO (-3250 4025);
DISPLAY INVISIBLE (-3250 4025);
FORCEPROP 1 LAST BODY_TYPE PLUMBING
J 0
(-3250 4075);
DISPLAY 0.872340 (-3250 4075);
PAINT GREEN (-3250 4075);
DISPLAY INVISIBLE (-3250 4075);
FORCEPROP 1 LAST HDL_TAP TRUE
J 0
(-2925 3900);
DISPLAY 0.872340 (-2925 3900);
DISPLAY INVISIBLE (-2925 3900);
FORCEPROP 1 LAST PATH I209
J 0
(-3252 4025);
DISPLAY 0.872340 (-3252 4025);
PAINT GREEN (-3252 4025);
DISPLAY INVISIBLE (-3252 4025);
FORCEADD OFFPAGE..1
(-8075 5400);
FORCEPROP 2 LAST $XR0 43 
J 0
(-8296 5400);
DISPLAY 0.638298 (-8296 5400);
PAINT MONO (-8296 5400);
FORCEPROP 2 LAST CDS_LIB mstr_standard
J 0
(-8075 5400);
DISPLAY 0.723404 (-8075 5400);
PAINT MONO (-8075 5400);
DISPLAY INVISIBLE (-8075 5400);
FORCEPROP 1 LAST OFFPAGE TRUE
J 0
(-7750 5275);
DISPLAY 0.872340 (-7750 5275);
PAINT GREEN (-7750 5275);
DISPLAY INVISIBLE (-7750 5275);
FORCEPROP 1 LAST COMMENT_BODY TRUE
J 0
(-7950 5300);
DISPLAY 0.872340 (-7950 5300);
PAINT GREEN (-7950 5300);
DISPLAY INVISIBLE (-7950 5300);
FORCEPROP 2 LAST PATH I21
J 0
(-8325 5450);
DISPLAY 1.021277 (-8325 5450);
DISPLAY INVISIBLE (-8325 5450);
FORCEADD TAP..1
(-3250 3925);
FORCEPROP 3 LASTPIN (-3300 3925) SIG_NAME M_G_CPU1_SA_DQS_DP<4>
J 0
(-3290 3935);
DISPLAY 0.659574 (-3290 3935);
PAINT MONO (-3290 3935);
DISPLAY INVISIBLE (-3290 3935);
FORCEPROP 1 LASTPIN (-3300 3925) BN 4
J 0
(-3312 3933);
DISPLAY 0.489362 (-3312 3933);
PAINT GREEN (-3312 3933);
FORCEPROP 2 LAST CDS_LIB mstr_standard
J 0
(-3250 3925);
DISPLAY 0.723404 (-3250 3925);
PAINT MONO (-3250 3925);
DISPLAY INVISIBLE (-3250 3925);
FORCEPROP 1 LAST BODY_TYPE PLUMBING
J 0
(-3250 3975);
DISPLAY 0.872340 (-3250 3975);
PAINT GREEN (-3250 3975);
DISPLAY INVISIBLE (-3250 3975);
FORCEPROP 1 LAST HDL_TAP TRUE
J 0
(-2925 3800);
DISPLAY 0.872340 (-2925 3800);
DISPLAY INVISIBLE (-2925 3800);
FORCEPROP 1 LAST PATH I210
J 0
(-3252 3925);
DISPLAY 0.872340 (-3252 3925);
PAINT GREEN (-3252 3925);
DISPLAY INVISIBLE (-3252 3925);
FORCEADD TAP..1
(-3250 3825);
FORCEPROP 3 LASTPIN (-3300 3825) SIG_NAME M_G_CPU1_SA_DQS_DP<3>
J 0
(-3290 3835);
DISPLAY 0.659574 (-3290 3835);
PAINT MONO (-3290 3835);
DISPLAY INVISIBLE (-3290 3835);
FORCEPROP 1 LASTPIN (-3300 3825) BN 3
J 0
(-3312 3833);
DISPLAY 0.489362 (-3312 3833);
PAINT GREEN (-3312 3833);
FORCEPROP 2 LAST CDS_LIB mstr_standard
J 0
(-3250 3825);
DISPLAY 0.723404 (-3250 3825);
PAINT MONO (-3250 3825);
DISPLAY INVISIBLE (-3250 3825);
FORCEPROP 1 LAST BODY_TYPE PLUMBING
J 0
(-3250 3875);
DISPLAY 0.872340 (-3250 3875);
PAINT GREEN (-3250 3875);
DISPLAY INVISIBLE (-3250 3875);
FORCEPROP 1 LAST HDL_TAP TRUE
J 0
(-2925 3700);
DISPLAY 0.872340 (-2925 3700);
DISPLAY INVISIBLE (-2925 3700);
FORCEPROP 1 LAST PATH I211
J 0
(-3252 3825);
DISPLAY 0.872340 (-3252 3825);
PAINT GREEN (-3252 3825);
DISPLAY INVISIBLE (-3252 3825);
FORCEADD TAP..1
(-3050 3675);
FORCEPROP 3 LASTPIN (-3100 3675) SIG_NAME M_G_CPU1_SA_DQS_DN<2>
J 0
(-3090 3685);
DISPLAY 0.659574 (-3090 3685);
PAINT MONO (-3090 3685);
DISPLAY INVISIBLE (-3090 3685);
FORCEPROP 1 LASTPIN (-3100 3675) BN 2
J 0
(-3112 3683);
DISPLAY 0.489362 (-3112 3683);
PAINT GREEN (-3112 3683);
FORCEPROP 2 LAST CDS_LIB mstr_standard
J 0
(-3050 3675);
DISPLAY 0.723404 (-3050 3675);
PAINT MONO (-3050 3675);
DISPLAY INVISIBLE (-3050 3675);
FORCEPROP 1 LAST BODY_TYPE PLUMBING
J 0
(-3050 3725);
DISPLAY 0.872340 (-3050 3725);
PAINT GREEN (-3050 3725);
DISPLAY INVISIBLE (-3050 3725);
FORCEPROP 1 LAST HDL_TAP TRUE
J 0
(-2725 3550);
DISPLAY 0.872340 (-2725 3550);
DISPLAY INVISIBLE (-2725 3550);
FORCEPROP 1 LAST PATH I212
J 0
(-3052 3675);
DISPLAY 0.872340 (-3052 3675);
PAINT GREEN (-3052 3675);
DISPLAY INVISIBLE (-3052 3675);
FORCEADD TAP..1
(-3050 3575);
FORCEPROP 3 LASTPIN (-3100 3575) SIG_NAME M_G_CPU1_SA_DQS_DN<1>
J 0
(-3090 3585);
DISPLAY 0.659574 (-3090 3585);
PAINT MONO (-3090 3585);
DISPLAY INVISIBLE (-3090 3585);
FORCEPROP 1 LASTPIN (-3100 3575) BN 1
J 0
(-3112 3583);
DISPLAY 0.489362 (-3112 3583);
PAINT GREEN (-3112 3583);
FORCEPROP 2 LAST CDS_LIB mstr_standard
J 0
(-3050 3575);
DISPLAY 0.723404 (-3050 3575);
PAINT MONO (-3050 3575);
DISPLAY INVISIBLE (-3050 3575);
FORCEPROP 1 LAST BODY_TYPE PLUMBING
J 0
(-3050 3625);
DISPLAY 0.872340 (-3050 3625);
PAINT GREEN (-3050 3625);
DISPLAY INVISIBLE (-3050 3625);
FORCEPROP 1 LAST HDL_TAP TRUE
J 0
(-2725 3450);
DISPLAY 0.872340 (-2725 3450);
DISPLAY INVISIBLE (-2725 3450);
FORCEPROP 1 LAST PATH I213
J 0
(-3052 3575);
DISPLAY 0.872340 (-3052 3575);
PAINT GREEN (-3052 3575);
DISPLAY INVISIBLE (-3052 3575);
FORCEADD TAP..1
(-3050 3475);
FORCEPROP 3 LASTPIN (-3100 3475) SIG_NAME M_G_CPU1_SA_DQS_DN<0>
J 0
(-3090 3485);
DISPLAY 0.659574 (-3090 3485);
PAINT MONO (-3090 3485);
DISPLAY INVISIBLE (-3090 3485);
FORCEPROP 1 LASTPIN (-3100 3475) BN 0
J 0
(-3112 3483);
DISPLAY 0.489362 (-3112 3483);
PAINT GREEN (-3112 3483);
FORCEPROP 2 LAST CDS_LIB mstr_standard
J 0
(-3050 3475);
DISPLAY 0.723404 (-3050 3475);
PAINT MONO (-3050 3475);
DISPLAY INVISIBLE (-3050 3475);
FORCEPROP 1 LAST BODY_TYPE PLUMBING
J 0
(-3050 3525);
DISPLAY 0.872340 (-3050 3525);
PAINT GREEN (-3050 3525);
DISPLAY INVISIBLE (-3050 3525);
FORCEPROP 1 LAST HDL_TAP TRUE
J 0
(-2725 3350);
DISPLAY 0.872340 (-2725 3350);
DISPLAY INVISIBLE (-2725 3350);
FORCEPROP 1 LAST PATH I214
J 0
(-3052 3475);
DISPLAY 0.872340 (-3052 3475);
PAINT GREEN (-3052 3475);
DISPLAY INVISIBLE (-3052 3475);
FORCEADD TAP..1
(-3050 3325);
FORCEPROP 3 LASTPIN (-3100 3325) SIG_NAME M_G_CPU1_SB_DQS_DN<9>
J 0
(-3090 3335);
DISPLAY 0.659574 (-3090 3335);
PAINT MONO (-3090 3335);
DISPLAY INVISIBLE (-3090 3335);
FORCEPROP 1 LASTPIN (-3100 3325) BN 9
J 0
(-3112 3333);
DISPLAY 0.489362 (-3112 3333);
PAINT GREEN (-3112 3333);
FORCEPROP 2 LAST CDS_LIB mstr_standard
J 0
(-3050 3325);
DISPLAY 0.723404 (-3050 3325);
PAINT MONO (-3050 3325);
DISPLAY INVISIBLE (-3050 3325);
FORCEPROP 1 LAST BODY_TYPE PLUMBING
J 0
(-3050 3375);
DISPLAY 0.872340 (-3050 3375);
PAINT GREEN (-3050 3375);
DISPLAY INVISIBLE (-3050 3375);
FORCEPROP 1 LAST HDL_TAP TRUE
J 0
(-2725 3200);
DISPLAY 0.872340 (-2725 3200);
DISPLAY INVISIBLE (-2725 3200);
FORCEPROP 1 LAST PATH I215
J 0
(-3052 3325);
DISPLAY 0.872340 (-3052 3325);
PAINT GREEN (-3052 3325);
DISPLAY INVISIBLE (-3052 3325);
FORCEADD TAP..1
(-3050 3225);
FORCEPROP 3 LASTPIN (-3100 3225) SIG_NAME M_G_CPU1_SB_DQS_DN<8>
J 0
(-3090 3235);
DISPLAY 0.659574 (-3090 3235);
PAINT MONO (-3090 3235);
DISPLAY INVISIBLE (-3090 3235);
FORCEPROP 1 LASTPIN (-3100 3225) BN 8
J 0
(-3112 3233);
DISPLAY 0.489362 (-3112 3233);
PAINT GREEN (-3112 3233);
FORCEPROP 2 LAST CDS_LIB mstr_standard
J 0
(-3050 3225);
DISPLAY 0.723404 (-3050 3225);
PAINT MONO (-3050 3225);
DISPLAY INVISIBLE (-3050 3225);
FORCEPROP 1 LAST BODY_TYPE PLUMBING
J 0
(-3050 3275);
DISPLAY 0.872340 (-3050 3275);
PAINT GREEN (-3050 3275);
DISPLAY INVISIBLE (-3050 3275);
FORCEPROP 1 LAST HDL_TAP TRUE
J 0
(-2725 3100);
DISPLAY 0.872340 (-2725 3100);
DISPLAY INVISIBLE (-2725 3100);
FORCEPROP 1 LAST PATH I216
J 0
(-3052 3225);
DISPLAY 0.872340 (-3052 3225);
PAINT GREEN (-3052 3225);
DISPLAY INVISIBLE (-3052 3225);
FORCEADD TAP..1
(-3250 3725);
FORCEPROP 3 LASTPIN (-3300 3725) SIG_NAME M_G_CPU1_SA_DQS_DP<2>
J 0
(-3290 3735);
DISPLAY 0.659574 (-3290 3735);
PAINT MONO (-3290 3735);
DISPLAY INVISIBLE (-3290 3735);
FORCEPROP 1 LASTPIN (-3300 3725) BN 2
J 0
(-3312 3733);
DISPLAY 0.489362 (-3312 3733);
PAINT GREEN (-3312 3733);
FORCEPROP 2 LAST CDS_LIB mstr_standard
J 0
(-3250 3725);
DISPLAY 0.723404 (-3250 3725);
PAINT MONO (-3250 3725);
DISPLAY INVISIBLE (-3250 3725);
FORCEPROP 1 LAST BODY_TYPE PLUMBING
J 0
(-3250 3775);
DISPLAY 0.872340 (-3250 3775);
PAINT GREEN (-3250 3775);
DISPLAY INVISIBLE (-3250 3775);
FORCEPROP 1 LAST HDL_TAP TRUE
J 0
(-2925 3600);
DISPLAY 0.872340 (-2925 3600);
DISPLAY INVISIBLE (-2925 3600);
FORCEPROP 1 LAST PATH I217
J 0
(-3252 3725);
DISPLAY 0.872340 (-3252 3725);
PAINT GREEN (-3252 3725);
DISPLAY INVISIBLE (-3252 3725);
FORCEADD TAP..1
(-3250 3625);
FORCEPROP 3 LASTPIN (-3300 3625) SIG_NAME M_G_CPU1_SA_DQS_DP<1>
J 0
(-3290 3635);
DISPLAY 0.659574 (-3290 3635);
PAINT MONO (-3290 3635);
DISPLAY INVISIBLE (-3290 3635);
FORCEPROP 1 LASTPIN (-3300 3625) BN 1
J 0
(-3312 3633);
DISPLAY 0.489362 (-3312 3633);
PAINT GREEN (-3312 3633);
FORCEPROP 2 LAST CDS_LIB mstr_standard
J 0
(-3250 3625);
DISPLAY 0.723404 (-3250 3625);
PAINT MONO (-3250 3625);
DISPLAY INVISIBLE (-3250 3625);
FORCEPROP 1 LAST BODY_TYPE PLUMBING
J 0
(-3250 3675);
DISPLAY 0.872340 (-3250 3675);
PAINT GREEN (-3250 3675);
DISPLAY INVISIBLE (-3250 3675);
FORCEPROP 1 LAST HDL_TAP TRUE
J 0
(-2925 3500);
DISPLAY 0.872340 (-2925 3500);
DISPLAY INVISIBLE (-2925 3500);
FORCEPROP 1 LAST PATH I218
J 0
(-3252 3625);
DISPLAY 0.872340 (-3252 3625);
PAINT GREEN (-3252 3625);
DISPLAY INVISIBLE (-3252 3625);
FORCEADD TAP..1
(-3250 3525);
FORCEPROP 3 LASTPIN (-3300 3525) SIG_NAME M_G_CPU1_SA_DQS_DP<0>
J 0
(-3290 3535);
DISPLAY 0.659574 (-3290 3535);
PAINT MONO (-3290 3535);
DISPLAY INVISIBLE (-3290 3535);
FORCEPROP 1 LASTPIN (-3300 3525) BN 0
J 0
(-3312 3533);
DISPLAY 0.489362 (-3312 3533);
PAINT GREEN (-3312 3533);
FORCEPROP 2 LAST CDS_LIB mstr_standard
J 0
(-3250 3525);
DISPLAY 0.723404 (-3250 3525);
PAINT MONO (-3250 3525);
DISPLAY INVISIBLE (-3250 3525);
FORCEPROP 1 LAST BODY_TYPE PLUMBING
J 0
(-3250 3575);
DISPLAY 0.872340 (-3250 3575);
PAINT GREEN (-3250 3575);
DISPLAY INVISIBLE (-3250 3575);
FORCEPROP 1 LAST HDL_TAP TRUE
J 0
(-2925 3400);
DISPLAY 0.872340 (-2925 3400);
DISPLAY INVISIBLE (-2925 3400);
FORCEPROP 1 LAST PATH I219
J 0
(-3252 3525);
DISPLAY 0.872340 (-3252 3525);
PAINT GREEN (-3252 3525);
DISPLAY INVISIBLE (-3252 3525);
FORCEADD SCONN288_DDR506112002KQ..1
(-6625 3600);
FORCEPROP 1 LAST LOCATION J102
J 0
(-7075 5675);
DISPLAY 0.468085 (-7075 5675);
PAINT SKYBLUE (-7075 5675);
FORCEPROP 0 LAST $SEC 1
J 0
(-7075 5825);
DISPLAY 0.680851 (-7075 5825);
PAINT MONO (-7075 5825);
DISPLAY INVISIBLE (-7075 5825);
FORCEPROP 0 LAST CDS_SEC 1
J 0
(-7075 5825);
DISPLAY 0.680851 (-7075 5825);
DISPLAY INVISIBLE (-7075 5825);
FORCEPROP 0 LASTPIN (-7225 3000) $PN 62
J 2
(-7235 3010);
DISPLAY 0.680851 (-7235 3010);
PAINT MONO (-7235 3010);
FORCEPROP 0 LASTPIN (-7225 5050) $PN 66
J 2
(-7235 5060);
DISPLAY 0.680851 (-7235 5060);
PAINT MONO (-7235 5060);
FORCEPROP 0 LASTPIN (-7225 4650) $PN 76
J 2
(-7235 4660);
DISPLAY 0.680851 (-7235 4660);
PAINT MONO (-7235 4660);
FORCEPROP 0 LASTPIN (-7225 5100) $PN 211
J 2
(-7235 5110);
DISPLAY 0.680851 (-7235 5110);
PAINT MONO (-7235 5110);
FORCEPROP 0 LASTPIN (-7225 4700) $PN 221
J 2
(-7235 4710);
DISPLAY 0.680851 (-7235 4710);
PAINT MONO (-7235 4710);
FORCEPROP 0 LASTPIN (-7225 5150) $PN 68
J 2
(-7235 5160);
DISPLAY 0.680851 (-7235 5160);
PAINT MONO (-7235 5160);
FORCEPROP 0 LASTPIN (-7225 4750) $PN 78
J 2
(-7235 4760);
DISPLAY 0.680851 (-7235 4760);
PAINT MONO (-7235 4760);
FORCEPROP 0 LASTPIN (-7225 5200) $PN 213
J 2
(-7235 5210);
DISPLAY 0.680851 (-7235 5210);
PAINT MONO (-7235 5210);
FORCEPROP 0 LASTPIN (-7225 4800) $PN 223
J 2
(-7235 4810);
DISPLAY 0.680851 (-7235 4810);
PAINT MONO (-7235 4810);
FORCEPROP 0 LASTPIN (-7225 5250) $PN 70
J 2
(-7235 5260);
DISPLAY 0.680851 (-7235 5260);
PAINT MONO (-7235 5260);
FORCEPROP 0 LASTPIN (-7225 4850) $PN 80
J 2
(-7235 4860);
DISPLAY 0.680851 (-7235 4860);
PAINT MONO (-7235 4860);
FORCEPROP 0 LASTPIN (-7225 5300) $PN 215
J 2
(-7235 5310);
DISPLAY 0.680851 (-7235 5310);
PAINT MONO (-7235 5310);
FORCEPROP 0 LASTPIN (-7225 4900) $PN 225
J 2
(-7235 4910);
DISPLAY 0.680851 (-7235 4910);
PAINT MONO (-7235 4910);
FORCEPROP 0 LASTPIN (-7225 5350) $PN 72
J 2
(-7235 5360);
DISPLAY 0.680851 (-7235 5360);
PAINT MONO (-7235 5360);
FORCEPROP 0 LASTPIN (-7225 4950) $PN 82
J 2
(-7235 4960);
DISPLAY 0.680851 (-7235 4960);
PAINT MONO (-7235 4960);
FORCEPROP 0 LASTPIN (-7225 3600) $PN 51
J 2
(-7235 3610);
DISPLAY 0.680851 (-7235 3610);
PAINT MONO (-7235 3610);
FORCEPROP 0 LASTPIN (-7225 3150) $PN 96
J 2
(-7235 3160);
DISPLAY 0.680851 (-7235 3160);
PAINT MONO (-7235 3160);
FORCEPROP 0 LASTPIN (-7225 3650) $PN 53
J 2
(-7235 3660);
DISPLAY 0.680851 (-7235 3660);
PAINT MONO (-7235 3660);
FORCEPROP 0 LASTPIN (-7225 3200) $PN 98
J 2
(-7235 3210);
DISPLAY 0.680851 (-7235 3210);
PAINT MONO (-7235 3210);
FORCEPROP 0 LASTPIN (-7225 3700) $PN 196
J 2
(-7235 3710);
DISPLAY 0.680851 (-7235 3710);
PAINT MONO (-7235 3710);
FORCEPROP 0 LASTPIN (-7225 3250) $PN 241
J 2
(-7235 3260);
DISPLAY 0.680851 (-7235 3260);
PAINT MONO (-7235 3260);
FORCEPROP 0 LASTPIN (-7225 3750) $PN 198
J 2
(-7235 3760);
DISPLAY 0.680851 (-7235 3760);
PAINT MONO (-7235 3760);
FORCEPROP 0 LASTPIN (-7225 3300) $PN 243
J 2
(-7235 3310);
DISPLAY 0.680851 (-7235 3310);
PAINT MONO (-7235 3310);
FORCEPROP 0 LASTPIN (-7225 3800) $PN 58
J 2
(-7235 3810);
DISPLAY 0.680851 (-7235 3810);
PAINT MONO (-7235 3810);
FORCEPROP 0 LASTPIN (-7225 3350) $PN 89
J 2
(-7235 3360);
DISPLAY 0.680851 (-7235 3360);
PAINT MONO (-7235 3360);
FORCEPROP 0 LASTPIN (-7225 3850) $PN 60
J 2
(-7235 3860);
DISPLAY 0.680851 (-7235 3860);
PAINT MONO (-7235 3860);
FORCEPROP 0 LASTPIN (-7225 3400) $PN 91
J 2
(-7235 3410);
DISPLAY 0.680851 (-7235 3410);
PAINT MONO (-7235 3410);
FORCEPROP 0 LASTPIN (-7225 3900) $PN 203
J 2
(-7235 3910);
DISPLAY 0.680851 (-7235 3910);
PAINT MONO (-7235 3910);
FORCEPROP 0 LASTPIN (-7225 3450) $PN 234
J 2
(-7235 3460);
DISPLAY 0.680851 (-7235 3460);
PAINT MONO (-7235 3460);
FORCEPROP 0 LASTPIN (-7225 3950) $PN 205
J 2
(-7235 3960);
DISPLAY 0.680851 (-7235 3960);
PAINT MONO (-7235 3960);
FORCEPROP 0 LASTPIN (-7225 3500) $PN 236
J 2
(-7235 3510);
DISPLAY 0.680851 (-7235 3510);
PAINT MONO (-7235 3510);
FORCEPROP 0 LASTPIN (-7225 4050) $PN 218
J 2
(-7235 4060);
DISPLAY 0.680851 (-7235 4060);
PAINT MONO (-7235 4060);
FORCEPROP 0 LASTPIN (-7225 4100) $PN 217
J 2
(-7235 4110);
DISPLAY 0.680851 (-7235 4110);
PAINT MONO (-7235 4110);
FORCEPROP 0 LASTPIN (-7225 4350) $PN 64
J 2
(-7235 4360);
DISPLAY 0.680851 (-7235 4360);
PAINT MONO (-7235 4360);
FORCEPROP 0 LASTPIN (-7225 4200) $PN 84
J 2
(-7235 4210);
DISPLAY 0.680851 (-7235 4210);
PAINT MONO (-7235 4210);
FORCEPROP 0 LASTPIN (-7225 4400) $PN 209
J 2
(-7235 4410);
DISPLAY 0.680851 (-7235 4410);
PAINT MONO (-7235 4410);
FORCEPROP 0 LASTPIN (-7225 4250) $PN 229
J 2
(-7235 4260);
DISPLAY 0.680851 (-7235 4260);
PAINT MONO (-7235 4260);
FORCEPROP 0 LASTPIN (-6025 3800) $PN 7
J 0
(-6015 3810);
DISPLAY 0.680851 (-6015 3810);
PAINT MONO (-6015 3810);
FORCEPROP 0 LASTPIN (-6025 2150) $PN 100
J 0
(-6015 2160);
DISPLAY 0.680851 (-6015 2160);
PAINT MONO (-6015 2160);
FORCEPROP 0 LASTPIN (-6025 3850) $PN 9
J 0
(-6015 3860);
DISPLAY 0.680851 (-6015 3860);
PAINT MONO (-6015 3860);
FORCEPROP 0 LASTPIN (-6025 2200) $PN 102
J 0
(-6015 2210);
DISPLAY 0.680851 (-6015 2210);
PAINT MONO (-6015 2210);
FORCEPROP 0 LASTPIN (-6025 3900) $PN 152
J 0
(-6015 3910);
DISPLAY 0.680851 (-6015 3910);
PAINT MONO (-6015 3910);
FORCEPROP 0 LASTPIN (-6025 2250) $PN 245
J 0
(-6015 2260);
DISPLAY 0.680851 (-6015 2260);
PAINT MONO (-6015 2260);
FORCEPROP 0 LASTPIN (-6025 3950) $PN 154
J 0
(-6015 3960);
DISPLAY 0.680851 (-6015 3960);
PAINT MONO (-6015 3960);
FORCEPROP 0 LASTPIN (-6025 2300) $PN 247
J 0
(-6015 2310);
DISPLAY 0.680851 (-6015 2310);
PAINT MONO (-6015 2310);
FORCEPROP 0 LASTPIN (-6025 4000) $PN 14
J 0
(-6015 4010);
DISPLAY 0.680851 (-6015 4010);
PAINT MONO (-6015 4010);
FORCEPROP 0 LASTPIN (-6025 2350) $PN 107
J 0
(-6015 2360);
DISPLAY 0.680851 (-6015 2360);
PAINT MONO (-6015 2360);
FORCEPROP 0 LASTPIN (-6025 4050) $PN 16
J 0
(-6015 4060);
DISPLAY 0.680851 (-6015 4060);
PAINT MONO (-6015 4060);
FORCEPROP 0 LASTPIN (-6025 2400) $PN 109
J 0
(-6015 2410);
DISPLAY 0.680851 (-6015 2410);
PAINT MONO (-6015 2410);
FORCEPROP 0 LASTPIN (-6025 4100) $PN 159
J 0
(-6015 4110);
DISPLAY 0.680851 (-6015 4110);
PAINT MONO (-6015 4110);
FORCEPROP 0 LASTPIN (-6025 2450) $PN 252
J 0
(-6015 2460);
DISPLAY 0.680851 (-6015 2460);
PAINT MONO (-6015 2460);
FORCEPROP 0 LASTPIN (-6025 4150) $PN 161
J 0
(-6015 4160);
DISPLAY 0.680851 (-6015 4160);
PAINT MONO (-6015 4160);
FORCEPROP 0 LASTPIN (-6025 2500) $PN 254
J 0
(-6015 2510);
DISPLAY 0.680851 (-6015 2510);
PAINT MONO (-6015 2510);
FORCEPROP 0 LASTPIN (-6025 4200) $PN 18
J 0
(-6015 4210);
DISPLAY 0.680851 (-6015 4210);
PAINT MONO (-6015 4210);
FORCEPROP 0 LASTPIN (-6025 2550) $PN 111
J 0
(-6015 2560);
DISPLAY 0.680851 (-6015 2560);
PAINT MONO (-6015 2560);
FORCEPROP 0 LASTPIN (-6025 4250) $PN 20
J 0
(-6015 4260);
DISPLAY 0.680851 (-6015 4260);
PAINT MONO (-6015 4260);
FORCEPROP 0 LASTPIN (-6025 2600) $PN 113
J 0
(-6015 2610);
DISPLAY 0.680851 (-6015 2610);
PAINT MONO (-6015 2610);
FORCEPROP 0 LASTPIN (-6025 4300) $PN 163
J 0
(-6015 4310);
DISPLAY 0.680851 (-6015 4310);
PAINT MONO (-6015 4310);
FORCEPROP 0 LASTPIN (-6025 2650) $PN 256
J 0
(-6015 2660);
DISPLAY 0.680851 (-6015 2660);
PAINT MONO (-6015 2660);
FORCEPROP 0 LASTPIN (-6025 4350) $PN 165
J 0
(-6015 4360);
DISPLAY 0.680851 (-6015 4360);
PAINT MONO (-6015 4360);
FORCEPROP 0 LASTPIN (-6025 2700) $PN 258
J 0
(-6015 2710);
DISPLAY 0.680851 (-6015 2710);
PAINT MONO (-6015 2710);
FORCEPROP 0 LASTPIN (-6025 4400) $PN 25
J 0
(-6015 4410);
DISPLAY 0.680851 (-6015 4410);
PAINT MONO (-6015 4410);
FORCEPROP 0 LASTPIN (-6025 2750) $PN 118
J 0
(-6015 2760);
DISPLAY 0.680851 (-6015 2760);
PAINT MONO (-6015 2760);
FORCEPROP 0 LASTPIN (-6025 4450) $PN 27
J 0
(-6015 4460);
DISPLAY 0.680851 (-6015 4460);
PAINT MONO (-6015 4460);
FORCEPROP 0 LASTPIN (-6025 2800) $PN 120
J 0
(-6015 2810);
DISPLAY 0.680851 (-6015 2810);
PAINT MONO (-6015 2810);
FORCEPROP 0 LASTPIN (-6025 4500) $PN 170
J 0
(-6015 4510);
DISPLAY 0.680851 (-6015 4510);
PAINT MONO (-6015 4510);
FORCEPROP 0 LASTPIN (-6025 2850) $PN 263
J 0
(-6015 2860);
DISPLAY 0.680851 (-6015 2860);
PAINT MONO (-6015 2860);
FORCEPROP 0 LASTPIN (-6025 4550) $PN 172
J 0
(-6015 4560);
DISPLAY 0.680851 (-6015 4560);
PAINT MONO (-6015 4560);
FORCEPROP 0 LASTPIN (-6025 2900) $PN 265
J 0
(-6015 2910);
DISPLAY 0.680851 (-6015 2910);
PAINT MONO (-6015 2910);
FORCEPROP 0 LASTPIN (-6025 4600) $PN 29
J 0
(-6015 4610);
DISPLAY 0.680851 (-6015 4610);
PAINT MONO (-6015 4610);
FORCEPROP 0 LASTPIN (-6025 2950) $PN 122
J 0
(-6015 2960);
DISPLAY 0.680851 (-6015 2960);
PAINT MONO (-6015 2960);
FORCEPROP 0 LASTPIN (-6025 4650) $PN 31
J 0
(-6015 4660);
DISPLAY 0.680851 (-6015 4660);
PAINT MONO (-6015 4660);
FORCEPROP 0 LASTPIN (-6025 3000) $PN 124
J 0
(-6015 3010);
DISPLAY 0.680851 (-6015 3010);
PAINT MONO (-6015 3010);
FORCEPROP 0 LASTPIN (-6025 4700) $PN 174
J 0
(-6015 4710);
DISPLAY 0.680851 (-6015 4710);
PAINT MONO (-6015 4710);
FORCEPROP 0 LASTPIN (-6025 3050) $PN 267
J 0
(-6015 3060);
DISPLAY 0.680851 (-6015 3060);
PAINT MONO (-6015 3060);
FORCEPROP 0 LASTPIN (-6025 4750) $PN 176
J 0
(-6015 4760);
DISPLAY 0.680851 (-6015 4760);
PAINT MONO (-6015 4760);
FORCEPROP 0 LASTPIN (-6025 3100) $PN 269
J 0
(-6015 3110);
DISPLAY 0.680851 (-6015 3110);
PAINT MONO (-6015 3110);
FORCEPROP 0 LASTPIN (-6025 4800) $PN 36
J 0
(-6015 4810);
DISPLAY 0.680851 (-6015 4810);
PAINT MONO (-6015 4810);
FORCEPROP 0 LASTPIN (-6025 3150) $PN 129
J 0
(-6015 3160);
DISPLAY 0.680851 (-6015 3160);
PAINT MONO (-6015 3160);
FORCEPROP 0 LASTPIN (-6025 4850) $PN 38
J 0
(-6015 4860);
DISPLAY 0.680851 (-6015 4860);
PAINT MONO (-6015 4860);
FORCEPROP 0 LASTPIN (-6025 3200) $PN 131
J 0
(-6015 3210);
DISPLAY 0.680851 (-6015 3210);
PAINT MONO (-6015 3210);
FORCEPROP 0 LASTPIN (-6025 4900) $PN 181
J 0
(-6015 4910);
DISPLAY 0.680851 (-6015 4910);
PAINT MONO (-6015 4910);
FORCEPROP 0 LASTPIN (-6025 3250) $PN 274
J 0
(-6015 3260);
DISPLAY 0.680851 (-6015 3260);
PAINT MONO (-6015 3260);
FORCEPROP 0 LASTPIN (-6025 4950) $PN 183
J 0
(-6015 4960);
DISPLAY 0.680851 (-6015 4960);
PAINT MONO (-6015 4960);
FORCEPROP 0 LASTPIN (-6025 3300) $PN 276
J 0
(-6015 3310);
DISPLAY 0.680851 (-6015 3310);
PAINT MONO (-6015 3310);
FORCEPROP 0 LASTPIN (-6025 5000) $PN 40
J 0
(-6015 5010);
DISPLAY 0.680851 (-6015 5010);
PAINT MONO (-6015 5010);
FORCEPROP 0 LASTPIN (-6025 3350) $PN 133
J 0
(-6015 3360);
DISPLAY 0.680851 (-6015 3360);
PAINT MONO (-6015 3360);
FORCEPROP 0 LASTPIN (-6025 5050) $PN 42
J 0
(-6015 5060);
DISPLAY 0.680851 (-6015 5060);
PAINT MONO (-6015 5060);
FORCEPROP 0 LASTPIN (-6025 3400) $PN 135
J 0
(-6015 3410);
DISPLAY 0.680851 (-6015 3410);
PAINT MONO (-6015 3410);
FORCEPROP 0 LASTPIN (-6025 5100) $PN 185
J 0
(-6015 5110);
DISPLAY 0.680851 (-6015 5110);
PAINT MONO (-6015 5110);
FORCEPROP 0 LASTPIN (-6025 3450) $PN 278
J 0
(-6015 3460);
DISPLAY 0.680851 (-6015 3460);
PAINT MONO (-6015 3460);
FORCEPROP 0 LASTPIN (-6025 5150) $PN 187
J 0
(-6015 5160);
DISPLAY 0.680851 (-6015 5160);
PAINT MONO (-6015 5160);
FORCEPROP 0 LASTPIN (-6025 3500) $PN 280
J 0
(-6015 3510);
DISPLAY 0.680851 (-6015 3510);
PAINT MONO (-6015 3510);
FORCEPROP 0 LASTPIN (-6025 5200) $PN 47
J 0
(-6015 5210);
DISPLAY 0.680851 (-6015 5210);
PAINT MONO (-6015 5210);
FORCEPROP 0 LASTPIN (-6025 3550) $PN 140
J 0
(-6015 3560);
DISPLAY 0.680851 (-6015 3560);
PAINT MONO (-6015 3560);
FORCEPROP 0 LASTPIN (-6025 5250) $PN 49
J 0
(-6015 5260);
DISPLAY 0.680851 (-6015 5260);
PAINT MONO (-6015 5260);
FORCEPROP 0 LASTPIN (-6025 3600) $PN 142
J 0
(-6015 3610);
DISPLAY 0.680851 (-6015 3610);
PAINT MONO (-6015 3610);
FORCEPROP 0 LASTPIN (-6025 5300) $PN 192
J 0
(-6015 5310);
DISPLAY 0.680851 (-6015 5310);
PAINT MONO (-6015 5310);
FORCEPROP 0 LASTPIN (-6025 3650) $PN 285
J 0
(-6015 3660);
DISPLAY 0.680851 (-6015 3660);
PAINT MONO (-6015 3660);
FORCEPROP 0 LASTPIN (-6025 5350) $PN 194
J 0
(-6015 5360);
DISPLAY 0.680851 (-6015 5360);
PAINT MONO (-6015 5360);
FORCEPROP 0 LASTPIN (-6025 3700) $PN 287
J 0
(-6015 3710);
DISPLAY 0.680851 (-6015 3710);
PAINT MONO (-6015 3710);
FORCEPROP 0 LASTPIN (-7225 2850) $PN 148
J 2
(-7235 2860);
DISPLAY 0.680851 (-7235 2860);
PAINT MONO (-7235 2860);
FORCEPROP 0 LASTPIN (-7225 2750) $PN 4
J 2
(-7235 2760);
DISPLAY 0.680851 (-7235 2760);
PAINT MONO (-7235 2760);
FORCEPROP 0 LASTPIN (-7225 2800) $PN 5
J 2
(-7235 2810);
DISPLAY 0.680851 (-7235 2810);
PAINT MONO (-7235 2810);
FORCEPROP 0 LASTPIN (-7225 1950) $PN 86
J 2
(-7235 1960);
DISPLAY 0.680851 (-7235 1960);
PAINT MONO (-7235 1960);
FORCEPROP 0 LASTPIN (-7225 1900) $PN 87
J 2
(-7235 1910);
DISPLAY 0.680851 (-7235 1910);
PAINT MONO (-7235 1910);
FORCEPROP 0 LASTPIN (-7225 4550) $PN 74
J 2
(-7235 4560);
DISPLAY 0.680851 (-7235 4560);
PAINT MONO (-7235 4560);
FORCEPROP 0 LASTPIN (-7225 4500) $PN 227
J 2
(-7235 4510);
DISPLAY 0.680851 (-7235 4510);
PAINT MONO (-7235 4510);
FORCEPROP 0 LASTPIN (-7225 2500) $PN 147
J 2
(-7235 2510);
DISPLAY 0.680851 (-7235 2510);
PAINT MONO (-7235 2510);
FORCEPROP 0 LASTPIN (-7225 3050) $PN 207
J 2
(-7235 3060);
DISPLAY 0.680851 (-7235 3060);
PAINT MONO (-7235 3060);
FORCEPROP 0 LASTPIN (-7225 2100) $PN 2
J 2
(-7235 2110);
DISPLAY 0.680851 (-7235 2110);
PAINT MONO (-7235 2110);
FORCEPROP 0 LASTPIN (-7225 2150) $PN 144
J 2
(-7235 2160);
DISPLAY 0.680851 (-7235 2160);
PAINT MONO (-7235 2160);
FORCEPROP 0 LASTPIN (-7225 2200) $PN 149
J 2
(-7235 2210);
DISPLAY 0.680851 (-7235 2210);
PAINT MONO (-7235 2210);
FORCEPROP 0 LASTPIN (-7225 2250) $PN 150
J 2
(-7235 2260);
DISPLAY 0.680851 (-7235 2260);
PAINT MONO (-7235 2260);
FORCEPROP 0 LASTPIN (-7225 2300) $PN 220
J 2
(-7235 2310);
DISPLAY 0.680851 (-7235 2310);
PAINT MONO (-7235 2310);
FORCEPROP 0 LASTPIN (-7225 2350) $PN 231
J 2
(-7235 2360);
DISPLAY 0.680851 (-7235 2360);
PAINT MONO (-7235 2360);
FORCEPROP 0 LASTPIN (-7225 2400) $PN 232
J 2
(-7235 2410);
DISPLAY 0.680851 (-7235 2410);
PAINT MONO (-7235 2410);
FORCEPROP 0 LASTPIN (-7225 2900) $PN 3
J 2
(-7235 2910);
DISPLAY 0.680851 (-7235 2910);
PAINT MONO (-7235 2910);
FORCEPROP 1 LAST MATERIAL IO
J 0
(-7075 5525);
DISPLAY 0.468085 (-7075 5525);
PAINT SKYBLUE (-7075 5525);
FORCEPROP 2 LAST PART_TYPE SMLF
J 0
(-7075 5775);
DISPLAY 1.021277 (-7075 5775);
FORCEPROP 2 LAST VALUE SCONN288_DDR506112002KQ
J 0
(-7075 5725);
DISPLAY 0.489362 (-7075 5725);
PAINT SKYBLUE (-7075 5725);
FORCEPROP 2 LAST CDS_LIB pure_quanta
J 0
(-6625 3600);
DISPLAY INVISIBLE (-6625 3600);
FORCEPROP 1 LAST NEEDS_NO_SIZE TRUE
J 0
(-6625 3600);
DISPLAY 0.723404 (-6625 3600);
PAINT GREEN (-6625 3600);
DISPLAY INVISIBLE (-6625 3600);
FORCEPROP 1 LAST CDS_LMAN_SYM_OUTLINE -450,1900,450,-1850
J 0
(-6625 3600);
DISPLAY 0.468085 (-6625 3600);
PAINT GREEN (-6625 3600);
DISPLAY INVISIBLE (-6625 3600);
FORCEPROP 1 LAST PATH I22
J 0
(-6625 3600);
DISPLAY 0.723404 (-6625 3600);
PAINT GREEN (-6625 3600);
DISPLAY INVISIBLE (-6625 3600);
FORCEPROP 1 LAST PART_NUMBER DFHST8FS479
J 0
(-7075 5600);
DISPLAY 0.468085 (-7075 5600);
PAINT SKYBLUE (-7075 5600);
DISPLAY INVISIBLE (-7075 5600);
FORCEADD TAP..1
(-3250 3375);
FORCEPROP 3 LASTPIN (-3300 3375) SIG_NAME M_G_CPU1_SB_DQS_DP<9>
J 0
(-3290 3385);
DISPLAY 0.659574 (-3290 3385);
PAINT MONO (-3290 3385);
DISPLAY INVISIBLE (-3290 3385);
FORCEPROP 1 LASTPIN (-3300 3375) BN 9
J 0
(-3312 3383);
DISPLAY 0.489362 (-3312 3383);
PAINT GREEN (-3312 3383);
FORCEPROP 2 LAST CDS_LIB mstr_standard
J 0
(-3250 3375);
DISPLAY 0.723404 (-3250 3375);
PAINT MONO (-3250 3375);
DISPLAY INVISIBLE (-3250 3375);
FORCEPROP 1 LAST BODY_TYPE PLUMBING
J 0
(-3250 3425);
DISPLAY 0.872340 (-3250 3425);
PAINT GREEN (-3250 3425);
DISPLAY INVISIBLE (-3250 3425);
FORCEPROP 1 LAST HDL_TAP TRUE
J 0
(-2925 3250);
DISPLAY 0.872340 (-2925 3250);
DISPLAY INVISIBLE (-2925 3250);
FORCEPROP 1 LAST PATH I220
J 0
(-3252 3375);
DISPLAY 0.872340 (-3252 3375);
PAINT GREEN (-3252 3375);
DISPLAY INVISIBLE (-3252 3375);
FORCEADD TAP..1
(-3250 3275);
FORCEPROP 3 LASTPIN (-3300 3275) SIG_NAME M_G_CPU1_SB_DQS_DP<8>
J 0
(-3290 3285);
DISPLAY 0.659574 (-3290 3285);
PAINT MONO (-3290 3285);
DISPLAY INVISIBLE (-3290 3285);
FORCEPROP 1 LASTPIN (-3300 3275) BN 8
J 0
(-3312 3283);
DISPLAY 0.489362 (-3312 3283);
PAINT GREEN (-3312 3283);
FORCEPROP 2 LAST CDS_LIB mstr_standard
J 0
(-3250 3275);
DISPLAY 0.723404 (-3250 3275);
PAINT MONO (-3250 3275);
DISPLAY INVISIBLE (-3250 3275);
FORCEPROP 1 LAST BODY_TYPE PLUMBING
J 0
(-3250 3325);
DISPLAY 0.872340 (-3250 3325);
PAINT GREEN (-3250 3325);
DISPLAY INVISIBLE (-3250 3325);
FORCEPROP 1 LAST HDL_TAP TRUE
J 0
(-2925 3150);
DISPLAY 0.872340 (-2925 3150);
DISPLAY INVISIBLE (-2925 3150);
FORCEPROP 1 LAST PATH I221
J 0
(-3252 3275);
DISPLAY 0.872340 (-3252 3275);
PAINT GREEN (-3252 3275);
DISPLAY INVISIBLE (-3252 3275);
FORCEADD TAP..1
(-3050 3125);
FORCEPROP 3 LASTPIN (-3100 3125) SIG_NAME M_G_CPU1_SB_DQS_DN<7>
J 0
(-3090 3135);
DISPLAY 0.659574 (-3090 3135);
PAINT MONO (-3090 3135);
DISPLAY INVISIBLE (-3090 3135);
FORCEPROP 1 LASTPIN (-3100 3125) BN 7
J 0
(-3112 3133);
DISPLAY 0.489362 (-3112 3133);
PAINT GREEN (-3112 3133);
FORCEPROP 2 LAST CDS_LIB mstr_standard
J 0
(-3050 3125);
DISPLAY 0.723404 (-3050 3125);
PAINT MONO (-3050 3125);
DISPLAY INVISIBLE (-3050 3125);
FORCEPROP 1 LAST BODY_TYPE PLUMBING
J 0
(-3050 3175);
DISPLAY 0.872340 (-3050 3175);
PAINT GREEN (-3050 3175);
DISPLAY INVISIBLE (-3050 3175);
FORCEPROP 1 LAST HDL_TAP TRUE
J 0
(-2725 3000);
DISPLAY 0.872340 (-2725 3000);
DISPLAY INVISIBLE (-2725 3000);
FORCEPROP 1 LAST PATH I222
J 0
(-3052 3125);
DISPLAY 0.872340 (-3052 3125);
PAINT GREEN (-3052 3125);
DISPLAY INVISIBLE (-3052 3125);
FORCEADD TAP..1
(-3050 3025);
FORCEPROP 3 LASTPIN (-3100 3025) SIG_NAME M_G_CPU1_SB_DQS_DN<6>
J 0
(-3090 3035);
DISPLAY 0.659574 (-3090 3035);
PAINT MONO (-3090 3035);
DISPLAY INVISIBLE (-3090 3035);
FORCEPROP 1 LASTPIN (-3100 3025) BN 6
J 0
(-3112 3033);
DISPLAY 0.489362 (-3112 3033);
PAINT GREEN (-3112 3033);
FORCEPROP 2 LAST CDS_LIB mstr_standard
J 0
(-3050 3025);
DISPLAY 0.723404 (-3050 3025);
PAINT MONO (-3050 3025);
DISPLAY INVISIBLE (-3050 3025);
FORCEPROP 1 LAST BODY_TYPE PLUMBING
J 0
(-3050 3075);
DISPLAY 0.872340 (-3050 3075);
PAINT GREEN (-3050 3075);
DISPLAY INVISIBLE (-3050 3075);
FORCEPROP 1 LAST HDL_TAP TRUE
J 0
(-2725 2900);
DISPLAY 0.872340 (-2725 2900);
DISPLAY INVISIBLE (-2725 2900);
FORCEPROP 1 LAST PATH I223
J 0
(-3052 3025);
DISPLAY 0.872340 (-3052 3025);
PAINT GREEN (-3052 3025);
DISPLAY INVISIBLE (-3052 3025);
FORCEADD TAP..1
(-3050 2925);
FORCEPROP 3 LASTPIN (-3100 2925) SIG_NAME M_G_CPU1_SB_DQS_DN<5>
J 0
(-3090 2935);
DISPLAY 0.659574 (-3090 2935);
PAINT MONO (-3090 2935);
DISPLAY INVISIBLE (-3090 2935);
FORCEPROP 1 LASTPIN (-3100 2925) BN 5
J 0
(-3112 2933);
DISPLAY 0.489362 (-3112 2933);
PAINT GREEN (-3112 2933);
FORCEPROP 2 LAST CDS_LIB mstr_standard
J 0
(-3050 2925);
DISPLAY 0.723404 (-3050 2925);
PAINT MONO (-3050 2925);
DISPLAY INVISIBLE (-3050 2925);
FORCEPROP 1 LAST BODY_TYPE PLUMBING
J 0
(-3050 2975);
DISPLAY 0.872340 (-3050 2975);
PAINT GREEN (-3050 2975);
DISPLAY INVISIBLE (-3050 2975);
FORCEPROP 1 LAST HDL_TAP TRUE
J 0
(-2725 2800);
DISPLAY 0.872340 (-2725 2800);
DISPLAY INVISIBLE (-2725 2800);
FORCEPROP 1 LAST PATH I224
J 0
(-3052 2925);
DISPLAY 0.872340 (-3052 2925);
PAINT GREEN (-3052 2925);
DISPLAY INVISIBLE (-3052 2925);
FORCEADD TAP..1
(-3050 2825);
FORCEPROP 3 LASTPIN (-3100 2825) SIG_NAME M_G_CPU1_SB_DQS_DN<4>
J 0
(-3090 2835);
DISPLAY 0.659574 (-3090 2835);
PAINT MONO (-3090 2835);
DISPLAY INVISIBLE (-3090 2835);
FORCEPROP 1 LASTPIN (-3100 2825) BN 4
J 0
(-3112 2833);
DISPLAY 0.489362 (-3112 2833);
PAINT GREEN (-3112 2833);
FORCEPROP 2 LAST CDS_LIB mstr_standard
J 0
(-3050 2825);
DISPLAY 0.723404 (-3050 2825);
PAINT MONO (-3050 2825);
DISPLAY INVISIBLE (-3050 2825);
FORCEPROP 1 LAST BODY_TYPE PLUMBING
J 0
(-3050 2875);
DISPLAY 0.872340 (-3050 2875);
PAINT GREEN (-3050 2875);
DISPLAY INVISIBLE (-3050 2875);
FORCEPROP 1 LAST HDL_TAP TRUE
J 0
(-2725 2700);
DISPLAY 0.872340 (-2725 2700);
DISPLAY INVISIBLE (-2725 2700);
FORCEPROP 1 LAST PATH I225
J 0
(-3052 2825);
DISPLAY 0.872340 (-3052 2825);
PAINT GREEN (-3052 2825);
DISPLAY INVISIBLE (-3052 2825);
FORCEADD TAP..1
(-3050 2725);
FORCEPROP 3 LASTPIN (-3100 2725) SIG_NAME M_G_CPU1_SB_DQS_DN<3>
J 0
(-3090 2735);
DISPLAY 0.659574 (-3090 2735);
PAINT MONO (-3090 2735);
DISPLAY INVISIBLE (-3090 2735);
FORCEPROP 1 LASTPIN (-3100 2725) BN 3
J 0
(-3112 2733);
DISPLAY 0.489362 (-3112 2733);
PAINT GREEN (-3112 2733);
FORCEPROP 2 LAST CDS_LIB mstr_standard
J 0
(-3050 2725);
DISPLAY 0.723404 (-3050 2725);
PAINT MONO (-3050 2725);
DISPLAY INVISIBLE (-3050 2725);
FORCEPROP 1 LAST BODY_TYPE PLUMBING
J 0
(-3050 2775);
DISPLAY 0.872340 (-3050 2775);
PAINT GREEN (-3050 2775);
DISPLAY INVISIBLE (-3050 2775);
FORCEPROP 1 LAST HDL_TAP TRUE
J 0
(-2725 2600);
DISPLAY 0.872340 (-2725 2600);
DISPLAY INVISIBLE (-2725 2600);
FORCEPROP 1 LAST PATH I226
J 0
(-3052 2725);
DISPLAY 0.872340 (-3052 2725);
PAINT GREEN (-3052 2725);
DISPLAY INVISIBLE (-3052 2725);
FORCEADD TAP..1
(-3250 3175);
FORCEPROP 3 LASTPIN (-3300 3175) SIG_NAME M_G_CPU1_SB_DQS_DP<7>
J 0
(-3290 3185);
DISPLAY 0.659574 (-3290 3185);
PAINT MONO (-3290 3185);
DISPLAY INVISIBLE (-3290 3185);
FORCEPROP 1 LASTPIN (-3300 3175) BN 7
J 0
(-3312 3183);
DISPLAY 0.489362 (-3312 3183);
PAINT GREEN (-3312 3183);
FORCEPROP 2 LAST CDS_LIB mstr_standard
J 0
(-3250 3175);
DISPLAY 0.723404 (-3250 3175);
PAINT MONO (-3250 3175);
DISPLAY INVISIBLE (-3250 3175);
FORCEPROP 1 LAST BODY_TYPE PLUMBING
J 0
(-3250 3225);
DISPLAY 0.872340 (-3250 3225);
PAINT GREEN (-3250 3225);
DISPLAY INVISIBLE (-3250 3225);
FORCEPROP 1 LAST HDL_TAP TRUE
J 0
(-2925 3050);
DISPLAY 0.872340 (-2925 3050);
DISPLAY INVISIBLE (-2925 3050);
FORCEPROP 1 LAST PATH I227
J 0
(-3252 3175);
DISPLAY 0.872340 (-3252 3175);
PAINT GREEN (-3252 3175);
DISPLAY INVISIBLE (-3252 3175);
FORCEADD TAP..1
(-3250 3075);
FORCEPROP 3 LASTPIN (-3300 3075) SIG_NAME M_G_CPU1_SB_DQS_DP<6>
J 0
(-3290 3085);
DISPLAY 0.659574 (-3290 3085);
PAINT MONO (-3290 3085);
DISPLAY INVISIBLE (-3290 3085);
FORCEPROP 1 LASTPIN (-3300 3075) BN 6
J 0
(-3312 3083);
DISPLAY 0.489362 (-3312 3083);
PAINT GREEN (-3312 3083);
FORCEPROP 2 LAST CDS_LIB mstr_standard
J 0
(-3250 3075);
DISPLAY 0.723404 (-3250 3075);
PAINT MONO (-3250 3075);
DISPLAY INVISIBLE (-3250 3075);
FORCEPROP 1 LAST BODY_TYPE PLUMBING
J 0
(-3250 3125);
DISPLAY 0.872340 (-3250 3125);
PAINT GREEN (-3250 3125);
DISPLAY INVISIBLE (-3250 3125);
FORCEPROP 1 LAST HDL_TAP TRUE
J 0
(-2925 2950);
DISPLAY 0.872340 (-2925 2950);
DISPLAY INVISIBLE (-2925 2950);
FORCEPROP 1 LAST PATH I228
J 0
(-3252 3075);
DISPLAY 0.872340 (-3252 3075);
PAINT GREEN (-3252 3075);
DISPLAY INVISIBLE (-3252 3075);
FORCEADD TAP..1
(-3250 2975);
FORCEPROP 3 LASTPIN (-3300 2975) SIG_NAME M_G_CPU1_SB_DQS_DP<5>
J 0
(-3290 2985);
DISPLAY 0.659574 (-3290 2985);
PAINT MONO (-3290 2985);
DISPLAY INVISIBLE (-3290 2985);
FORCEPROP 1 LASTPIN (-3300 2975) BN 5
J 0
(-3312 2983);
DISPLAY 0.489362 (-3312 2983);
PAINT GREEN (-3312 2983);
FORCEPROP 2 LAST CDS_LIB mstr_standard
J 0
(-3250 2975);
DISPLAY 0.723404 (-3250 2975);
PAINT MONO (-3250 2975);
DISPLAY INVISIBLE (-3250 2975);
FORCEPROP 1 LAST BODY_TYPE PLUMBING
J 0
(-3250 3025);
DISPLAY 0.872340 (-3250 3025);
PAINT GREEN (-3250 3025);
DISPLAY INVISIBLE (-3250 3025);
FORCEPROP 1 LAST HDL_TAP TRUE
J 0
(-2925 2850);
DISPLAY 0.872340 (-2925 2850);
DISPLAY INVISIBLE (-2925 2850);
FORCEPROP 1 LAST PATH I229
J 0
(-3252 2975);
DISPLAY 0.872340 (-3252 2975);
PAINT GREEN (-3252 2975);
DISPLAY INVISIBLE (-3252 2975);
FORCEADD TAP..1
R 2
(-7475 3200);
FORCEPROP 3 LASTPIN (-7425 3200) SIG_NAME M_G_CPU1_SB_CB<1>
J 0
(-7415 3210);
DISPLAY 0.659574 (-7415 3210);
PAINT MONO (-7415 3210);
DISPLAY INVISIBLE (-7415 3210);
FORCEPROP 1 LASTPIN (-7425 3200) BN 1
J 2
(-7413 3208);
DISPLAY 0.489362 (-7413 3208);
PAINT GREEN (-7413 3208);
FORCEPROP 2 LAST CDS_LIB mstr_standard
J 0
(-7475 3200);
DISPLAY 0.723404 (-7475 3200);
PAINT MONO (-7475 3200);
DISPLAY INVISIBLE (-7475 3200);
FORCEPROP 1 LAST BODY_TYPE PLUMBING
J 2
(-7475 3250);
DISPLAY 0.872340 (-7475 3250);
PAINT GREEN (-7475 3250);
DISPLAY INVISIBLE (-7475 3250);
FORCEPROP 1 LAST HDL_TAP TRUE
J 2
(-7800 3075);
DISPLAY 0.872340 (-7800 3075);
DISPLAY INVISIBLE (-7800 3075);
FORCEPROP 1 LAST PATH I23
J 2
(-7473 3200);
DISPLAY 0.872340 (-7473 3200);
PAINT GREEN (-7473 3200);
DISPLAY INVISIBLE (-7473 3200);
FORCEADD TAP..1
(-3250 2875);
FORCEPROP 3 LASTPIN (-3300 2875) SIG_NAME M_G_CPU1_SB_DQS_DP<4>
J 0
(-3290 2885);
DISPLAY 0.659574 (-3290 2885);
PAINT MONO (-3290 2885);
DISPLAY INVISIBLE (-3290 2885);
FORCEPROP 1 LASTPIN (-3300 2875) BN 4
J 0
(-3312 2883);
DISPLAY 0.489362 (-3312 2883);
PAINT GREEN (-3312 2883);
FORCEPROP 2 LAST CDS_LIB mstr_standard
J 0
(-3250 2875);
DISPLAY 0.723404 (-3250 2875);
PAINT MONO (-3250 2875);
DISPLAY INVISIBLE (-3250 2875);
FORCEPROP 1 LAST BODY_TYPE PLUMBING
J 0
(-3250 2925);
DISPLAY 0.872340 (-3250 2925);
PAINT GREEN (-3250 2925);
DISPLAY INVISIBLE (-3250 2925);
FORCEPROP 1 LAST HDL_TAP TRUE
J 0
(-2925 2750);
DISPLAY 0.872340 (-2925 2750);
DISPLAY INVISIBLE (-2925 2750);
FORCEPROP 1 LAST PATH I230
J 0
(-3252 2875);
DISPLAY 0.872340 (-3252 2875);
PAINT GREEN (-3252 2875);
DISPLAY INVISIBLE (-3252 2875);
FORCEADD TAP..1
(-3250 2775);
FORCEPROP 3 LASTPIN (-3300 2775) SIG_NAME M_G_CPU1_SB_DQS_DP<3>
J 0
(-3290 2785);
DISPLAY 0.659574 (-3290 2785);
PAINT MONO (-3290 2785);
DISPLAY INVISIBLE (-3290 2785);
FORCEPROP 1 LASTPIN (-3300 2775) BN 3
J 0
(-3312 2783);
DISPLAY 0.489362 (-3312 2783);
PAINT GREEN (-3312 2783);
FORCEPROP 2 LAST CDS_LIB mstr_standard
J 0
(-3250 2775);
DISPLAY 0.723404 (-3250 2775);
PAINT MONO (-3250 2775);
DISPLAY INVISIBLE (-3250 2775);
FORCEPROP 1 LAST BODY_TYPE PLUMBING
J 0
(-3250 2825);
DISPLAY 0.872340 (-3250 2825);
PAINT GREEN (-3250 2825);
DISPLAY INVISIBLE (-3250 2825);
FORCEPROP 1 LAST HDL_TAP TRUE
J 0
(-2925 2650);
DISPLAY 0.872340 (-2925 2650);
DISPLAY INVISIBLE (-2925 2650);
FORCEPROP 1 LAST PATH I231
J 0
(-3252 2775);
DISPLAY 0.872340 (-3252 2775);
PAINT GREEN (-3252 2775);
DISPLAY INVISIBLE (-3252 2775);
FORCEADD TAP..1
(-3050 2625);
FORCEPROP 3 LASTPIN (-3100 2625) SIG_NAME M_G_CPU1_SB_DQS_DN<2>
J 0
(-3090 2635);
DISPLAY 0.659574 (-3090 2635);
PAINT MONO (-3090 2635);
DISPLAY INVISIBLE (-3090 2635);
FORCEPROP 1 LASTPIN (-3100 2625) BN 2
J 0
(-3112 2633);
DISPLAY 0.489362 (-3112 2633);
PAINT GREEN (-3112 2633);
FORCEPROP 2 LAST CDS_LIB mstr_standard
J 0
(-3050 2625);
DISPLAY 0.723404 (-3050 2625);
PAINT MONO (-3050 2625);
DISPLAY INVISIBLE (-3050 2625);
FORCEPROP 1 LAST BODY_TYPE PLUMBING
J 0
(-3050 2675);
DISPLAY 0.872340 (-3050 2675);
PAINT GREEN (-3050 2675);
DISPLAY INVISIBLE (-3050 2675);
FORCEPROP 1 LAST HDL_TAP TRUE
J 0
(-2725 2500);
DISPLAY 0.872340 (-2725 2500);
DISPLAY INVISIBLE (-2725 2500);
FORCEPROP 1 LAST PATH I232
J 0
(-3052 2625);
DISPLAY 0.872340 (-3052 2625);
PAINT GREEN (-3052 2625);
DISPLAY INVISIBLE (-3052 2625);
FORCEADD TAP..1
(-3050 2525);
FORCEPROP 3 LASTPIN (-3100 2525) SIG_NAME M_G_CPU1_SB_DQS_DN<1>
J 0
(-3090 2535);
DISPLAY 0.659574 (-3090 2535);
PAINT MONO (-3090 2535);
DISPLAY INVISIBLE (-3090 2535);
FORCEPROP 1 LASTPIN (-3100 2525) BN 1
J 0
(-3112 2533);
DISPLAY 0.489362 (-3112 2533);
PAINT GREEN (-3112 2533);
FORCEPROP 2 LAST CDS_LIB mstr_standard
J 0
(-3050 2525);
DISPLAY 0.723404 (-3050 2525);
PAINT MONO (-3050 2525);
DISPLAY INVISIBLE (-3050 2525);
FORCEPROP 1 LAST BODY_TYPE PLUMBING
J 0
(-3050 2575);
DISPLAY 0.872340 (-3050 2575);
PAINT GREEN (-3050 2575);
DISPLAY INVISIBLE (-3050 2575);
FORCEPROP 1 LAST HDL_TAP TRUE
J 0
(-2725 2400);
DISPLAY 0.872340 (-2725 2400);
DISPLAY INVISIBLE (-2725 2400);
FORCEPROP 1 LAST PATH I233
J 0
(-3052 2525);
DISPLAY 0.872340 (-3052 2525);
PAINT GREEN (-3052 2525);
DISPLAY INVISIBLE (-3052 2525);
FORCEADD TAP..1
(-3050 2425);
FORCEPROP 3 LASTPIN (-3100 2425) SIG_NAME M_G_CPU1_SB_DQS_DN<0>
J 0
(-3090 2435);
DISPLAY 0.659574 (-3090 2435);
PAINT MONO (-3090 2435);
DISPLAY INVISIBLE (-3090 2435);
FORCEPROP 1 LASTPIN (-3100 2425) BN 0
J 0
(-3112 2433);
DISPLAY 0.489362 (-3112 2433);
PAINT GREEN (-3112 2433);
FORCEPROP 2 LAST CDS_LIB mstr_standard
J 0
(-3050 2425);
DISPLAY 0.723404 (-3050 2425);
PAINT MONO (-3050 2425);
DISPLAY INVISIBLE (-3050 2425);
FORCEPROP 1 LAST BODY_TYPE PLUMBING
J 0
(-3050 2475);
DISPLAY 0.872340 (-3050 2475);
PAINT GREEN (-3050 2475);
DISPLAY INVISIBLE (-3050 2475);
FORCEPROP 1 LAST HDL_TAP TRUE
J 0
(-2725 2300);
DISPLAY 0.872340 (-2725 2300);
DISPLAY INVISIBLE (-2725 2300);
FORCEPROP 1 LAST PATH I234
J 0
(-3052 2425);
DISPLAY 0.872340 (-3052 2425);
PAINT GREEN (-3052 2425);
DISPLAY INVISIBLE (-3052 2425);
FORCEADD TAP..1
(-3250 2675);
FORCEPROP 3 LASTPIN (-3300 2675) SIG_NAME M_G_CPU1_SB_DQS_DP<2>
J 0
(-3290 2685);
DISPLAY 0.659574 (-3290 2685);
PAINT MONO (-3290 2685);
DISPLAY INVISIBLE (-3290 2685);
FORCEPROP 1 LASTPIN (-3300 2675) BN 2
J 0
(-3312 2683);
DISPLAY 0.489362 (-3312 2683);
PAINT GREEN (-3312 2683);
FORCEPROP 2 LAST CDS_LIB mstr_standard
J 0
(-3250 2675);
DISPLAY 0.723404 (-3250 2675);
PAINT MONO (-3250 2675);
DISPLAY INVISIBLE (-3250 2675);
FORCEPROP 1 LAST BODY_TYPE PLUMBING
J 0
(-3250 2725);
DISPLAY 0.872340 (-3250 2725);
PAINT GREEN (-3250 2725);
DISPLAY INVISIBLE (-3250 2725);
FORCEPROP 1 LAST HDL_TAP TRUE
J 0
(-2925 2550);
DISPLAY 0.872340 (-2925 2550);
DISPLAY INVISIBLE (-2925 2550);
FORCEPROP 1 LAST PATH I235
J 0
(-3252 2675);
DISPLAY 0.872340 (-3252 2675);
PAINT GREEN (-3252 2675);
DISPLAY INVISIBLE (-3252 2675);
FORCEADD TAP..1
(-3250 2575);
FORCEPROP 3 LASTPIN (-3300 2575) SIG_NAME M_G_CPU1_SB_DQS_DP<1>
J 0
(-3290 2585);
DISPLAY 0.659574 (-3290 2585);
PAINT MONO (-3290 2585);
DISPLAY INVISIBLE (-3290 2585);
FORCEPROP 1 LASTPIN (-3300 2575) BN 1
J 0
(-3312 2583);
DISPLAY 0.489362 (-3312 2583);
PAINT GREEN (-3312 2583);
FORCEPROP 2 LAST CDS_LIB mstr_standard
J 0
(-3250 2575);
DISPLAY 0.723404 (-3250 2575);
PAINT MONO (-3250 2575);
DISPLAY INVISIBLE (-3250 2575);
FORCEPROP 1 LAST BODY_TYPE PLUMBING
J 0
(-3250 2625);
DISPLAY 0.872340 (-3250 2625);
PAINT GREEN (-3250 2625);
DISPLAY INVISIBLE (-3250 2625);
FORCEPROP 1 LAST HDL_TAP TRUE
J 0
(-2925 2450);
DISPLAY 0.872340 (-2925 2450);
DISPLAY INVISIBLE (-2925 2450);
FORCEPROP 1 LAST PATH I236
J 0
(-3252 2575);
DISPLAY 0.872340 (-3252 2575);
PAINT GREEN (-3252 2575);
DISPLAY INVISIBLE (-3252 2575);
FORCEADD TAP..1
(-3250 2475);
FORCEPROP 3 LASTPIN (-3300 2475) SIG_NAME M_G_CPU1_SB_DQS_DP<0>
J 0
(-3290 2485);
DISPLAY 0.659574 (-3290 2485);
PAINT MONO (-3290 2485);
DISPLAY INVISIBLE (-3290 2485);
FORCEPROP 1 LASTPIN (-3300 2475) BN 0
J 0
(-3312 2483);
DISPLAY 0.489362 (-3312 2483);
PAINT GREEN (-3312 2483);
FORCEPROP 2 LAST CDS_LIB mstr_standard
J 0
(-3250 2475);
DISPLAY 0.723404 (-3250 2475);
PAINT MONO (-3250 2475);
DISPLAY INVISIBLE (-3250 2475);
FORCEPROP 1 LAST BODY_TYPE PLUMBING
J 0
(-3250 2525);
DISPLAY 0.872340 (-3250 2525);
PAINT GREEN (-3250 2525);
DISPLAY INVISIBLE (-3250 2525);
FORCEPROP 1 LAST HDL_TAP TRUE
J 0
(-2925 2350);
DISPLAY 0.872340 (-2925 2350);
DISPLAY INVISIBLE (-2925 2350);
FORCEPROP 1 LAST PATH I237
J 0
(-3252 2475);
DISPLAY 0.872340 (-3252 2475);
PAINT GREEN (-3252 2475);
DISPLAY INVISIBLE (-3252 2475);
FORCEADD SCONN288_DDR506112002KQ..2
(-4250 3425);
FORCEPROP 1 LAST LOCATION J102
J 0
(-4850 4750);
DISPLAY 0.468085 (-4850 4750);
PAINT SKYBLUE (-4850 4750);
FORCEPROP 0 LAST $SEC 2
J 0
(-4700 4900);
DISPLAY 0.680851 (-4700 4900);
PAINT MONO (-4700 4900);
DISPLAY INVISIBLE (-4700 4900);
FORCEPROP 2 LAST CDS_SEC 2
J 0
(-4700 4900);
DISPLAY 0.680851 (-4700 4900);
DISPLAY INVISIBLE (-4700 4900);
FORCEPROP 0 LASTPIN (-3500 3475) $PN 12
J 0
(-3490 3485);
DISPLAY 0.680851 (-3490 3485);
PAINT MONO (-3490 3485);
FORCEPROP 0 LASTPIN (-3500 3525) $PN 11
J 0
(-3490 3535);
DISPLAY 0.680851 (-3490 3535);
PAINT MONO (-3490 3535);
FORCEPROP 0 LASTPIN (-3500 2425) $PN 105
J 0
(-3490 2435);
DISPLAY 0.680851 (-3490 2435);
PAINT MONO (-3490 2435);
FORCEPROP 0 LASTPIN (-3500 2475) $PN 104
J 0
(-3490 2485);
DISPLAY 0.680851 (-3490 2485);
PAINT MONO (-3490 2485);
FORCEPROP 0 LASTPIN (-3500 3575) $PN 23
J 0
(-3490 3585);
DISPLAY 0.680851 (-3490 3585);
PAINT MONO (-3490 3585);
FORCEPROP 0 LASTPIN (-3500 3625) $PN 22
J 0
(-3490 3635);
DISPLAY 0.680851 (-3490 3635);
PAINT MONO (-3490 3635);
FORCEPROP 0 LASTPIN (-3500 2525) $PN 116
J 0
(-3490 2535);
DISPLAY 0.680851 (-3490 2535);
PAINT MONO (-3490 2535);
FORCEPROP 0 LASTPIN (-3500 2575) $PN 115
J 0
(-3490 2585);
DISPLAY 0.680851 (-3490 2585);
PAINT MONO (-3490 2585);
FORCEPROP 0 LASTPIN (-3500 3675) $PN 34
J 0
(-3490 3685);
DISPLAY 0.680851 (-3490 3685);
PAINT MONO (-3490 3685);
FORCEPROP 0 LASTPIN (-3500 3725) $PN 33
J 0
(-3490 3735);
DISPLAY 0.680851 (-3490 3735);
PAINT MONO (-3490 3735);
FORCEPROP 0 LASTPIN (-3500 2625) $PN 127
J 0
(-3490 2635);
DISPLAY 0.680851 (-3490 2635);
PAINT MONO (-3490 2635);
FORCEPROP 0 LASTPIN (-3500 2675) $PN 126
J 0
(-3490 2685);
DISPLAY 0.680851 (-3490 2685);
PAINT MONO (-3490 2685);
FORCEPROP 0 LASTPIN (-3500 3775) $PN 45
J 0
(-3490 3785);
DISPLAY 0.680851 (-3490 3785);
PAINT MONO (-3490 3785);
FORCEPROP 0 LASTPIN (-3500 3825) $PN 44
J 0
(-3490 3835);
DISPLAY 0.680851 (-3490 3835);
PAINT MONO (-3490 3835);
FORCEPROP 0 LASTPIN (-3500 2725) $PN 138
J 0
(-3490 2735);
DISPLAY 0.680851 (-3490 2735);
PAINT MONO (-3490 2735);
FORCEPROP 0 LASTPIN (-3500 2775) $PN 137
J 0
(-3490 2785);
DISPLAY 0.680851 (-3490 2785);
PAINT MONO (-3490 2785);
FORCEPROP 0 LASTPIN (-3500 3875) $PN 56
J 0
(-3490 3885);
DISPLAY 0.680851 (-3490 3885);
PAINT MONO (-3490 3885);
FORCEPROP 0 LASTPIN (-3500 3925) $PN 55
J 0
(-3490 3935);
DISPLAY 0.680851 (-3490 3935);
PAINT MONO (-3490 3935);
FORCEPROP 0 LASTPIN (-3500 2825) $PN 238
J 0
(-3490 2835);
DISPLAY 0.680851 (-3490 2835);
PAINT MONO (-3490 2835);
FORCEPROP 0 LASTPIN (-3500 2875) $PN 239
J 0
(-3490 2885);
DISPLAY 0.680851 (-3490 2885);
PAINT MONO (-3490 2885);
FORCEPROP 0 LASTPIN (-3500 3975) $PN 156
J 0
(-3490 3985);
DISPLAY 0.680851 (-3490 3985);
PAINT MONO (-3490 3985);
FORCEPROP 0 LASTPIN (-3500 4025) $PN 157
J 0
(-3490 4035);
DISPLAY 0.680851 (-3490 4035);
PAINT MONO (-3490 4035);
FORCEPROP 0 LASTPIN (-3500 2925) $PN 249
J 0
(-3490 2935);
DISPLAY 0.680851 (-3490 2935);
PAINT MONO (-3490 2935);
FORCEPROP 0 LASTPIN (-3500 2975) $PN 250
J 0
(-3490 2985);
DISPLAY 0.680851 (-3490 2985);
PAINT MONO (-3490 2985);
FORCEPROP 0 LASTPIN (-3500 4075) $PN 167
J 0
(-3490 4085);
DISPLAY 0.680851 (-3490 4085);
PAINT MONO (-3490 4085);
FORCEPROP 0 LASTPIN (-3500 4125) $PN 168
J 0
(-3490 4135);
DISPLAY 0.680851 (-3490 4135);
PAINT MONO (-3490 4135);
FORCEPROP 0 LASTPIN (-3500 3025) $PN 260
J 0
(-3490 3035);
DISPLAY 0.680851 (-3490 3035);
PAINT MONO (-3490 3035);
FORCEPROP 0 LASTPIN (-3500 3075) $PN 261
J 0
(-3490 3085);
DISPLAY 0.680851 (-3490 3085);
PAINT MONO (-3490 3085);
FORCEPROP 0 LASTPIN (-3500 4175) $PN 178
J 0
(-3490 4185);
DISPLAY 0.680851 (-3490 4185);
PAINT MONO (-3490 4185);
FORCEPROP 0 LASTPIN (-3500 4225) $PN 179
J 0
(-3490 4235);
DISPLAY 0.680851 (-3490 4235);
PAINT MONO (-3490 4235);
FORCEPROP 0 LASTPIN (-3500 3125) $PN 271
J 0
(-3490 3135);
DISPLAY 0.680851 (-3490 3135);
PAINT MONO (-3490 3135);
FORCEPROP 0 LASTPIN (-3500 3175) $PN 272
J 0
(-3490 3185);
DISPLAY 0.680851 (-3490 3185);
PAINT MONO (-3490 3185);
FORCEPROP 0 LASTPIN (-3500 4275) $PN 189
J 0
(-3490 4285);
DISPLAY 0.680851 (-3490 4285);
PAINT MONO (-3490 4285);
FORCEPROP 0 LASTPIN (-3500 4325) $PN 190
J 0
(-3490 4335);
DISPLAY 0.680851 (-3490 4335);
PAINT MONO (-3490 4335);
FORCEPROP 0 LASTPIN (-3500 3225) $PN 282
J 0
(-3490 3235);
DISPLAY 0.680851 (-3490 3235);
PAINT MONO (-3490 3235);
FORCEPROP 0 LASTPIN (-3500 3275) $PN 283
J 0
(-3490 3285);
DISPLAY 0.680851 (-3490 3285);
PAINT MONO (-3490 3285);
FORCEPROP 0 LASTPIN (-3500 4375) $PN 200
J 0
(-3490 4385);
DISPLAY 0.680851 (-3490 4385);
PAINT MONO (-3490 4385);
FORCEPROP 0 LASTPIN (-3500 4425) $PN 201
J 0
(-3490 4435);
DISPLAY 0.680851 (-3490 4435);
PAINT MONO (-3490 4435);
FORCEPROP 0 LASTPIN (-3500 3325) $PN 94
J 0
(-3490 3335);
DISPLAY 0.680851 (-3490 3335);
PAINT MONO (-3490 3335);
FORCEPROP 0 LASTPIN (-3500 3375) $PN 93
J 0
(-3490 3385);
DISPLAY 0.680851 (-3490 3385);
PAINT MONO (-3490 3385);
FORCEPROP 2 LAST PART_TYPE SMLF
J 0
(-4700 4850);
DISPLAY 1.021277 (-4700 4850);
FORCEPROP 1 LAST MATERIAL IO
J 0
(-4850 4600);
DISPLAY 0.468085 (-4850 4600);
PAINT SKYBLUE (-4850 4600);
FORCEPROP 2 LAST VALUE SCONN288_DDR506112002KQ
J 0
(-4700 4800);
DISPLAY 0.489362 (-4700 4800);
PAINT SKYBLUE (-4700 4800);
FORCEPROP 2 LAST CDS_LIB pure_quanta
J 0
(-4250 3425);
DISPLAY INVISIBLE (-4250 3425);
FORCEPROP 1 LAST NEEDS_NO_SIZE TRUE
J 0
(-4250 3425);
DISPLAY 0.723404 (-4250 3425);
PAINT GREEN (-4250 3425);
DISPLAY INVISIBLE (-4250 3425);
FORCEPROP 1 LAST CDS_LMAN_SYM_OUTLINE -600,1150,600,-1150
J 0
(-4250 3425);
DISPLAY 0.468085 (-4250 3425);
PAINT GREEN (-4250 3425);
DISPLAY INVISIBLE (-4250 3425);
FORCEPROP 1 LAST PATH I238
J 0
(-4250 3425);
DISPLAY 0.723404 (-4250 3425);
PAINT GREEN (-4250 3425);
DISPLAY INVISIBLE (-4250 3425);
FORCEPROP 1 LAST PART_NUMBER DFHST8FS479
J 0
(-4850 4675);
DISPLAY 0.468085 (-4850 4675);
PAINT SKYBLUE (-4850 4675);
DISPLAY INVISIBLE (-4850 4675);
FORCEADD GND..1
(-2825 5525);
FORCEPROP 3 LASTPIN (-2825 5575) SIG_NAME GND\g
J 0
(-2815 5585);
DISPLAY 0.659574 (-2815 5585);
PAINT MONO (-2815 5585);
DISPLAY INVISIBLE (-2815 5585);
FORCEPROP 2 LAST ROOM MEM_EFGH_DECOUPLING_CAPS
J 0
(-2800 5600);
DISPLAY 0.659574 (-2800 5600);
PAINT RED (-2800 5600);
DISPLAY INVISIBLE (-2800 5600);
FORCEPROP 1 LAST SIZE 1B
J 0
(-2750 5475);
DISPLAY 0.723404 (-2750 5475);
PAINT GREEN (-2750 5475);
DISPLAY INVISIBLE (-2750 5475);
FORCEPROP 2 LAST BOM_COST MEM
J 0
(-2800 5650);
DISPLAY 0.659574 (-2800 5650);
DISPLAY INVISIBLE (-2800 5650);
FORCEPROP 2 LAST CDS_LIB pure_quanta_power
J 0
(-2825 5525);
DISPLAY INVISIBLE (-2825 5525);
FORCEPROP 1 LAST HDL_POWER GND
J 0
(-2825 5675);
DISPLAY 0.723404 (-2825 5675);
PAINT GREEN (-2825 5675);
DISPLAY INVISIBLE (-2825 5675);
FORCEPROP 1 LAST PATH I239
J 0
(-2750 5525);
DISPLAY 0.872340 (-2750 5525);
PAINT AQUA (-2750 5525);
DISPLAY INVISIBLE (-2750 5525);
FORCEADD TAP..1
R 2
(-7475 3150);
FORCEPROP 3 LASTPIN (-7425 3150) SIG_NAME M_G_CPU1_SB_CB<0>
J 0
(-7415 3160);
DISPLAY 0.659574 (-7415 3160);
PAINT MONO (-7415 3160);
DISPLAY INVISIBLE (-7415 3160);
FORCEPROP 1 LASTPIN (-7425 3150) BN 0
J 2
(-7413 3158);
DISPLAY 0.489362 (-7413 3158);
PAINT GREEN (-7413 3158);
FORCEPROP 2 LAST CDS_LIB mstr_standard
J 0
(-7475 3150);
DISPLAY 0.723404 (-7475 3150);
PAINT MONO (-7475 3150);
DISPLAY INVISIBLE (-7475 3150);
FORCEPROP 1 LAST BODY_TYPE PLUMBING
J 2
(-7475 3200);
DISPLAY 0.872340 (-7475 3200);
PAINT GREEN (-7475 3200);
DISPLAY INVISIBLE (-7475 3200);
FORCEPROP 1 LAST HDL_TAP TRUE
J 2
(-7800 3025);
DISPLAY 0.872340 (-7800 3025);
DISPLAY INVISIBLE (-7800 3025);
FORCEPROP 1 LAST PATH I24
J 2
(-7473 3150);
DISPLAY 0.872340 (-7473 3150);
PAINT GREEN (-7473 3150);
DISPLAY INVISIBLE (-7473 3150);
FORCEADD Q_CAP..1
R 2
(-2825 5875);
FORCEPROP 1 LAST LOCATION C530
J 2
(-2875 5975);
DISPLAY 0.489362 (-2875 5975);
PAINT SKYBLUE (-2875 5975);
FORCEPROP 0 LAST $SEC 1
J 0
(-2875 6025);
DISPLAY 0.680851 (-2875 6025);
PAINT MONO (-2875 6025);
DISPLAY INVISIBLE (-2875 6025);
FORCEPROP 0 LAST CDS_SEC 1
J 0
(-2875 6025);
DISPLAY 0.680851 (-2875 6025);
DISPLAY INVISIBLE (-2875 6025);
FORCEPROP 1 LASTPIN (-2825 5975) $PN 1
J 2
(-2835 5955);
DISPLAY 0.489362 (-2835 5955);
PAINT MONO (-2835 5955);
FORCEPROP 1 LASTPIN (-2825 5775) $PN 2
J 2
(-2835 5755);
DISPLAY 0.489362 (-2835 5755);
PAINT MONO (-2835 5755);
FORCEPROP 1 LAST MATERIAL X6S
J 2
(-2875 5775);
DISPLAY 0.489362 (-2875 5775);
PAINT SKYBLUE (-2875 5775);
FORCEPROP 1 LAST TOLERANCE 10%
J 2
(-2875 5825);
DISPLAY 0.489362 (-2875 5825);
PAINT SKYBLUE (-2875 5825);
FORCEPROP 1 LAST VOLTAGE 25V
J 2
(-2875 5875);
DISPLAY 0.489362 (-2875 5875);
PAINT SKYBLUE (-2875 5875);
FORCEPROP 1 LAST PACK_TYPE C0805
J 2
(-2875 5675);
DISPLAY 0.489362 (-2875 5675);
PAINT SKYBLUE (-2875 5675);
FORCEPROP 1 LAST VALUE 10UF
J 2
(-2875 5925);
DISPLAY 0.489362 (-2875 5925);
PAINT SKYBLUE (-2875 5925);
FORCEPROP 0 LAST BOM_COST MEM
J 2
(-2880 6020);
DISPLAY 0.595745 (-2880 6020);
PAINT MONO (-2880 6020);
DISPLAY INVISIBLE (-2880 6020);
FORCEPROP 2 LAST CDS_LIB pure_quanta
J 0
(-2825 5875);
DISPLAY INVISIBLE (-2825 5875);
FORCEPROP 2 LAST ROOM 
J 2
(-2880 6020);
DISPLAY 0.595745 (-2880 6020);
PAINT RED (-2880 6020);
DISPLAY INVISIBLE (-2880 6020);
FORCEPROP 1 LAST PATH I240
J 2
(-2875 6025);
DISPLAY 0.978723 (-2875 6025);
PAINT WHITE (-2875 6025);
DISPLAY INVISIBLE (-2875 6025);
FORCEPROP 1 LAST PART_NUMBER CH6104KEA00
J 2
(-2875 5725);
DISPLAY 0.489362 (-2875 5725);
PAINT SKYBLUE (-2875 5725);
DISPLAY INVISIBLE (-2875 5725);
FORCEADD Q_CAP..1
R 2
(-2250 5875);
FORCEPROP 1 LAST LOCATION C531
J 2
(-2300 5975);
DISPLAY 0.489362 (-2300 5975);
PAINT SKYBLUE (-2300 5975);
FORCEPROP 0 LAST $SEC 1
J 0
(-2300 6025);
DISPLAY 0.680851 (-2300 6025);
PAINT MONO (-2300 6025);
DISPLAY INVISIBLE (-2300 6025);
FORCEPROP 0 LAST CDS_SEC 1
J 0
(-2300 6025);
DISPLAY 0.680851 (-2300 6025);
DISPLAY INVISIBLE (-2300 6025);
FORCEPROP 1 LASTPIN (-2250 5975) $PN 1
J 2
(-2260 5955);
DISPLAY 0.489362 (-2260 5955);
PAINT MONO (-2260 5955);
FORCEPROP 1 LASTPIN (-2250 5775) $PN 2
J 2
(-2260 5755);
DISPLAY 0.489362 (-2260 5755);
PAINT MONO (-2260 5755);
FORCEPROP 1 LAST TOLERANCE 10%
J 2
(-2300 5825);
DISPLAY 0.489362 (-2300 5825);
PAINT SKYBLUE (-2300 5825);
FORCEPROP 1 LAST VALUE 10UF
J 2
(-2300 5925);
DISPLAY 0.489362 (-2300 5925);
PAINT SKYBLUE (-2300 5925);
FORCEPROP 1 LAST VOLTAGE 25V
J 2
(-2300 5875);
DISPLAY 0.489362 (-2300 5875);
PAINT SKYBLUE (-2300 5875);
FORCEPROP 1 LAST PACK_TYPE C0805
J 2
(-2300 5675);
DISPLAY 0.489362 (-2300 5675);
PAINT SKYBLUE (-2300 5675);
FORCEPROP 1 LAST MATERIAL X6S
J 2
(-2300 5775);
DISPLAY 0.489362 (-2300 5775);
PAINT SKYBLUE (-2300 5775);
FORCEPROP 0 LAST BOM_COST MEM
J 2
(-2305 6020);
DISPLAY 0.595745 (-2305 6020);
PAINT MONO (-2305 6020);
DISPLAY INVISIBLE (-2305 6020);
FORCEPROP 2 LAST CDS_LIB pure_quanta
J 0
(-2250 5875);
DISPLAY INVISIBLE (-2250 5875);
FORCEPROP 2 LAST ROOM 
J 2
(-2305 6020);
DISPLAY 0.595745 (-2305 6020);
PAINT RED (-2305 6020);
DISPLAY INVISIBLE (-2305 6020);
FORCEPROP 1 LAST PATH I241
J 2
(-2300 6025);
DISPLAY 0.978723 (-2300 6025);
PAINT WHITE (-2300 6025);
DISPLAY INVISIBLE (-2300 6025);
FORCEPROP 1 LAST PART_NUMBER CH6104KEA00
J 2
(-2300 5725);
DISPLAY 0.489362 (-2300 5725);
PAINT SKYBLUE (-2300 5725);
DISPLAY INVISIBLE (-2300 5725);
FORCEADD UNIVERSAL_POWER..1
(-2825 6200);
FORCEPROP 3 LASTPIN (-2825 6150) SIG_NAME P12V_MEM_CPU1\g
J 0
(-2815 6160);
DISPLAY 0.659574 (-2815 6160);
PAINT MONO (-2815 6160);
DISPLAY INVISIBLE (-2815 6160);
FORCEPROP 1 LAST HDL_POWER P12V_MEM_CPU1
J 1
(-2825 6250);
DISPLAY 0.489362 (-2825 6250);
PAINT GREEN (-2825 6250);
FORCEPROP 2 LAST CDS_LIB pure_quanta_power
J 0
(-2825 6200);
DISPLAY INVISIBLE (-2825 6200);
FORCEPROP 1 LAST PATH I242
J 0
(-2775 6225);
DISPLAY 0.872340 (-2775 6225);
PAINT AQUA (-2775 6225);
DISPLAY INVISIBLE (-2775 6225);
FORCEADD OFFPAGE..1
(-8125 2575);
FORCEPROP 2 LAST $XR5 109 
J 0
(-8977 2575);
DISPLAY 0.638298 (-8977 2575);
PAINT MONO (-8977 2575);
FORCEPROP 2 LAST $XR4 108 
J 0
(-8857 2575);
DISPLAY 0.638298 (-8857 2575);
PAINT MONO (-8857 2575);
FORCEPROP 2 LAST $XR3 107 
J 0
(-8737 2575);
DISPLAY 0.638298 (-8737 2575);
PAINT MONO (-8737 2575);
FORCEPROP 2 LAST $XR2 106 
J 0
(-8617 2575);
DISPLAY 0.638298 (-8617 2575);
PAINT MONO (-8617 2575);
FORCEPROP 2 LAST $XR1 105 
J 0
(-8497 2575);
DISPLAY 0.638298 (-8497 2575);
PAINT MONO (-8497 2575);
FORCEPROP 2 LAST $XR0 159 
J 0
(-8377 2575);
DISPLAY 0.638298 (-8377 2575);
PAINT MONO (-8377 2575);
FORCEPROP 2 LAST CDS_LIB mstr_standard
J 0
(-8125 2575);
DISPLAY 0.808511 (-8125 2575);
DISPLAY INVISIBLE (-8125 2575);
FORCEPROP 1 LAST OFFPAGE TRUE
J 0
(-7800 2450);
DISPLAY 0.872340 (-7800 2450);
PAINT GREEN (-7800 2450);
DISPLAY INVISIBLE (-7800 2450);
FORCEPROP 1 LAST COMMENT_BODY TRUE
J 0
(-8000 2475);
DISPLAY 0.872340 (-8000 2475);
PAINT GREEN (-8000 2475);
DISPLAY INVISIBLE (-8000 2475);
FORCEPROP 2 LAST PATH I243
J 0
(-8400 2625);
DISPLAY 0.680851 (-8400 2625);
DISPLAY INVISIBLE (-8400 2625);
FORCEADD Q_RES..1
(-7525 2575);
FORCEPROP 1 LAST LOCATION R1586
J 0
(-7575 2600);
DISPLAY 0.510638 (-7575 2600);
PAINT SKYBLUE (-7575 2600);
FORCEPROP 0 LAST $SEC 1
J 0
(-7575 2675);
DISPLAY 0.680851 (-7575 2675);
PAINT MONO (-7575 2675);
DISPLAY INVISIBLE (-7575 2675);
FORCEPROP 0 LAST CDS_SEC 1
J 0
(-7575 2675);
DISPLAY 0.680851 (-7575 2675);
DISPLAY INVISIBLE (-7575 2675);
FORCEPROP 1 LASTPIN (-7625 2575) $PN 1
J 0
(-7613 2587);
DISPLAY 0.787234 (-7613 2587);
PAINT MONO (-7613 2587);
FORCEPROP 1 LASTPIN (-7425 2575) $PN 2
J 0
(-7463 2587);
DISPLAY 0.787234 (-7463 2587);
PAINT MONO (-7463 2587);
FORCEPROP 1 LAST VALUE 49.9
J 2
(-7375 2650);
DISPLAY 0.510638 (-7375 2650);
PAINT SKYBLUE (-7375 2650);
FORCEPROP 1 LAST MATERIAL CHIP
J 0
(-7525 2425);
DISPLAY 0.978723 (-7525 2425);
DISPLAY INVISIBLE (-7525 2425);
FORCEPROP 1 LAST PACK_TYPE 0402LF
J 0
(-7275 2425);
DISPLAY 0.978723 (-7275 2425);
DISPLAY INVISIBLE (-7275 2425);
FORCEPROP 1 LAST WATTAGE 1/16W
J 2
(-7550 2425);
DISPLAY 0.978723 (-7550 2425);
DISPLAY INVISIBLE (-7550 2425);
FORCEPROP 1 LAST TOLERANCE 1%
J 0
(-7525 2475);
DISPLAY 0.978723 (-7525 2475);
DISPLAY INVISIBLE (-7525 2475);
FORCEPROP 2 LAST CDS_LIB pure_quanta
J 0
(-7525 2575);
DISPLAY INVISIBLE (-7525 2575);
FORCEPROP 1 LAST PATH I244
J 0
(-7575 2725);
DISPLAY 0.978723 (-7575 2725);
PAINT WHITE (-7575 2725);
DISPLAY INVISIBLE (-7575 2725);
FORCEPROP 1 LAST PART_NUMBER CS04992FB07
J 0
(-7575 2675);
DISPLAY 0.978723 (-7575 2675);
DISPLAY INVISIBLE (-7575 2675);
FORCEADD Q_RES..2
(-8975 1375);
FORCEPROP 1 LAST LOCATION R8040
J 0
(-8930 1500);
DISPLAY 0.978723 (-8930 1500);
FORCEPROP 0 LAST $SEC 1
J 0
(-8925 1550);
DISPLAY 0.680851 (-8925 1550);
PAINT MONO (-8925 1550);
DISPLAY INVISIBLE (-8925 1550);
FORCEPROP 0 LAST CDS_SEC 1
J 0
(-8925 1550);
DISPLAY 0.680851 (-8925 1550);
DISPLAY INVISIBLE (-8925 1550);
FORCEPROP 1 LASTPIN (-8975 1475) $PN 1
J 0
(-8970 1437);
DISPLAY 0.787234 (-8970 1437);
PAINT MONO (-8970 1437);
FORCEPROP 1 LASTPIN (-8975 1275) $PN 2
J 0
(-8970 1285);
DISPLAY 0.787234 (-8970 1285);
PAINT MONO (-8970 1285);
FORCEPROP 1 LAST WATTAGE 1/16W
J 0
(-8935 1350);
DISPLAY 0.978723 (-8935 1350);
FORCEPROP 1 LAST MATERIAL CHIP
J 0
(-8935 1300);
DISPLAY 0.978723 (-8935 1300);
FORCEPROP 1 LAST VALUE 10K
J 0
(-8930 1450);
DISPLAY 0.978723 (-8930 1450);
FORCEPROP 1 LAST PACK_TYPE 0402LF
J 0
(-8935 1200);
DISPLAY 0.978723 (-8935 1200);
FORCEPROP 1 LAST TOLERANCE 1%
J 0
(-8930 1400);
DISPLAY 0.978723 (-8930 1400);
FORCEPROP 2 LAST CDS_LIB pure_quanta
J 0
(-8975 1375);
DISPLAY INVISIBLE (-8975 1375);
FORCEPROP 1 LAST PATH I245
J 0
(-8925 1550);
DISPLAY 0.978723 (-8925 1550);
PAINT WHITE (-8925 1550);
DISPLAY INVISIBLE (-8925 1550);
FORCEPROP 1 LAST PART_NUMBER CS31002FB08
J 0
(-8935 1250);
DISPLAY 0.978723 (-8935 1250);
DISPLAY INVISIBLE (-8935 1250);
FORCEADD VCC_CORE..1
(-8975 1675);
FORCEPROP 3 LASTPIN (-8975 1625) SIG_NAME P3V3_AUX\g
J 0
(-8965 1635);
DISPLAY 0.659574 (-8965 1635);
PAINT MONO (-8965 1635);
DISPLAY INVISIBLE (-8965 1635);
FORCEPROP 1 LAST HDL_POWER P3V3_AUX
J 1
(-8975 1725);
DISPLAY 0.489362 (-8975 1725);
PAINT GREEN (-8975 1725);
FORCEPROP 2 LAST CDS_LIB pure_quanta_power
J 0
(-8975 1675);
DISPLAY INVISIBLE (-8975 1675);
FORCEPROP 0 LAST VOLTAGE 3.3
J 0
(-9250 1825);
DISPLAY 1.021277 (-9250 1825);
PAINT SKYBLUE (-9250 1825);
DISPLAY INVISIBLE (-9250 1825);
FORCEPROP 2 LAST ROOM PVCCINFAON_CPU0_CTRL
J 0
(-8975 1775);
DISPLAY 0.808511 (-8975 1775);
PAINT RED (-8975 1775);
DISPLAY INVISIBLE (-8975 1775);
FORCEPROP 1 LAST PATH I246
J 0
(-8925 1700);
DISPLAY 0.872340 (-8925 1700);
PAINT AQUA (-8925 1700);
DISPLAY INVISIBLE (-8925 1700);
FORCEADD OFFPAGE..2
(-7950 975);
FORCEPROP 2 LAST $XR5 109 
J 0
(-7161 975);
DISPLAY 0.638298 (-7161 975);
PAINT MONO (-7161 975);
FORCEPROP 2 LAST $XR4 108 
J 0
(-7281 975);
DISPLAY 0.638298 (-7281 975);
PAINT MONO (-7281 975);
FORCEPROP 2 LAST $XR3 107 
J 0
(-7401 975);
DISPLAY 0.638298 (-7401 975);
PAINT MONO (-7401 975);
FORCEPROP 2 LAST $XR2 106 
J 0
(-7521 975);
DISPLAY 0.638298 (-7521 975);
PAINT MONO (-7521 975);
FORCEPROP 2 LAST $XR1 105 
J 0
(-7641 975);
DISPLAY 0.638298 (-7641 975);
PAINT MONO (-7641 975);
FORCEPROP 2 LAST $XR0 104 
J 0
(-7761 975);
DISPLAY 0.638298 (-7761 975);
PAINT MONO (-7761 975);
FORCEPROP 2 LAST CDS_LIB standard
J 0
(-7950 975);
DISPLAY INVISIBLE (-7950 975);
FORCEPROP 1 LAST OFFPAGE TRUE
J 0
(-7625 850);
DISPLAY 0.723404 (-7625 850);
PAINT GREEN (-7625 850);
DISPLAY INVISIBLE (-7625 850);
FORCEPROP 1 LAST COMMENT_BODY TRUE
J 0
(-7995 880);
DISPLAY 0.872340 (-7995 880);
PAINT GREEN (-7995 880);
DISPLAY INVISIBLE (-7995 880);
FORCEPROP 2 LAST PATH I247
J 0
(-7775 1050);
DISPLAY 0.680851 (-7775 1050);
DISPLAY INVISIBLE (-7775 1050);
FORCEADD OFFPAGE..6
(-4750 750);
FORCEPROP 2 LAST $XR5 109 
J 0
(-5630 750);
DISPLAY 0.638298 (-5630 750);
PAINT MONO (-5630 750);
FORCEPROP 2 LAST $XR4 108 
J 0
(-5510 750);
DISPLAY 0.638298 (-5510 750);
PAINT MONO (-5510 750);
FORCEPROP 2 LAST $XR3 107 
J 0
(-5390 750);
DISPLAY 0.638298 (-5390 750);
PAINT MONO (-5390 750);
FORCEPROP 2 LAST $XR2 106 
J 0
(-5270 750);
DISPLAY 0.638298 (-5270 750);
PAINT MONO (-5270 750);
FORCEPROP 2 LAST $XR1 105 
J 0
(-5150 750);
DISPLAY 0.638298 (-5150 750);
PAINT MONO (-5150 750);
FORCEPROP 2 LAST $XR0 104 
J 0
(-5030 750);
DISPLAY 0.638298 (-5030 750);
PAINT MONO (-5030 750);
FORCEPROP 2 LAST CDS_LIB standard
J 0
(-4750 750);
DISPLAY INVISIBLE (-4750 750);
FORCEPROP 1 LAST OFFPAGE TRUE
J 0
(-4425 625);
DISPLAY 0.872340 (-4425 625);
PAINT GREEN (-4425 625);
DISPLAY INVISIBLE (-4425 625);
FORCEPROP 1 LAST COMMENT_BODY TRUE
J 0
(-4650 675);
DISPLAY 0.872340 (-4650 675);
PAINT GREEN (-4650 675);
DISPLAY INVISIBLE (-4650 675);
FORCEPROP 2 LAST PATH I248
J 0
(-4700 825);
DISPLAY 0.680851 (-4700 825);
DISPLAY INVISIBLE (-4700 825);
FORCEADD Q_RES..1
(-3850 750);
FORCEPROP 1 LAST LOCATION R8089
J 0
(-3900 800);
DISPLAY 0.978723 (-3900 800);
FORCEPROP 0 LAST $SEC 1
J 0
(-3900 850);
DISPLAY 0.680851 (-3900 850);
PAINT MONO (-3900 850);
DISPLAY INVISIBLE (-3900 850);
FORCEPROP 0 LAST CDS_SEC 1
J 0
(-3900 850);
DISPLAY 0.680851 (-3900 850);
DISPLAY INVISIBLE (-3900 850);
FORCEPROP 1 LASTPIN (-3950 750) $PN 1
J 0
(-3938 762);
DISPLAY 0.787234 (-3938 762);
PAINT MONO (-3938 762);
FORCEPROP 1 LASTPIN (-3750 750) $PN 2
J 0
(-3788 762);
DISPLAY 0.787234 (-3788 762);
PAINT MONO (-3788 762);
FORCEPROP 1 LAST MATERIAL CHIP
J 0
(-3850 600);
DISPLAY 0.978723 (-3850 600);
FORCEPROP 1 LAST WATTAGE 1/16W
J 2
(-3875 600);
DISPLAY 0.978723 (-3875 600);
FORCEPROP 1 LAST PACK_TYPE 0402LF
J 0
(-3600 600);
DISPLAY 0.978723 (-3600 600);
FORCEPROP 1 LAST TOLERANCE 5%
J 0
(-3850 650);
DISPLAY 0.978723 (-3850 650);
FORCEPROP 1 LAST VALUE 0
J 2
(-3875 650);
DISPLAY 0.978723 (-3875 650);
FORCEPROP 2 LAST CDS_LIB pure_quanta
J 0
(-3850 750);
DISPLAY INVISIBLE (-3850 750);
FORCEPROP 1 LAST PATH I249
J 0
(-3900 900);
DISPLAY 0.978723 (-3900 900);
PAINT WHITE (-3900 900);
DISPLAY INVISIBLE (-3900 900);
FORCEPROP 1 LAST PART_NUMBER CS00002JB13
J 0
(-4075 550);
DISPLAY 0.978723 (-4075 550);
DISPLAY INVISIBLE (-4075 550);
FORCEADD TAP..1
R 2
(-7475 3350);
FORCEPROP 3 LASTPIN (-7425 3350) SIG_NAME M_G_CPU1_SB_CB<4>
J 0
(-7415 3360);
DISPLAY 0.659574 (-7415 3360);
PAINT MONO (-7415 3360);
DISPLAY INVISIBLE (-7415 3360);
FORCEPROP 1 LASTPIN (-7425 3350) BN 4
J 2
(-7413 3358);
DISPLAY 0.489362 (-7413 3358);
PAINT GREEN (-7413 3358);
FORCEPROP 2 LAST CDS_LIB mstr_standard
J 0
(-7475 3350);
DISPLAY 0.723404 (-7475 3350);
PAINT MONO (-7475 3350);
DISPLAY INVISIBLE (-7475 3350);
FORCEPROP 1 LAST BODY_TYPE PLUMBING
J 2
(-7475 3400);
DISPLAY 0.872340 (-7475 3400);
PAINT GREEN (-7475 3400);
DISPLAY INVISIBLE (-7475 3400);
FORCEPROP 1 LAST HDL_TAP TRUE
J 2
(-7800 3225);
DISPLAY 0.872340 (-7800 3225);
DISPLAY INVISIBLE (-7800 3225);
FORCEPROP 1 LAST PATH I25
J 2
(-7473 3350);
DISPLAY 0.872340 (-7473 3350);
PAINT GREEN (-7473 3350);
DISPLAY INVISIBLE (-7473 3350);
FORCEADD VCC_CORE..1
(-4875 1425);
FORCEPROP 3 LASTPIN (-4875 1375) SIG_NAME P3V3_AUX\g
J 0
(-4865 1385);
DISPLAY 0.659574 (-4865 1385);
PAINT MONO (-4865 1385);
DISPLAY INVISIBLE (-4865 1385);
FORCEPROP 1 LAST HDL_POWER P3V3_AUX
J 1
(-4875 1475);
DISPLAY 0.489362 (-4875 1475);
PAINT GREEN (-4875 1475);
FORCEPROP 2 LAST CDS_LIB pure_quanta_power
J 0
(-4875 1425);
DISPLAY INVISIBLE (-4875 1425);
FORCEPROP 0 LAST VOLTAGE 3.3
J 0
(-5150 1575);
DISPLAY 1.021277 (-5150 1575);
PAINT SKYBLUE (-5150 1575);
DISPLAY INVISIBLE (-5150 1575);
FORCEPROP 2 LAST ROOM PVCCINFAON_CPU0_CTRL
J 0
(-4875 1525);
DISPLAY 0.808511 (-4875 1525);
PAINT RED (-4875 1525);
DISPLAY INVISIBLE (-4875 1525);
FORCEPROP 1 LAST PATH I250
J 0
(-4825 1450);
DISPLAY 0.872340 (-4825 1450);
PAINT AQUA (-4825 1450);
DISPLAY INVISIBLE (-4825 1450);
FORCEADD Q_RES..1
(-4275 1225);
FORCEPROP 1 LAST LOCATION R8091
J 0
(-4325 1275);
DISPLAY 0.978723 (-4325 1275);
FORCEPROP 0 LAST $SEC 1
J 0
(-4325 1400);
DISPLAY 0.680851 (-4325 1400);
PAINT MONO (-4325 1400);
DISPLAY INVISIBLE (-4325 1400);
FORCEPROP 0 LAST CDS_SEC 1
J 0
(-4325 1400);
DISPLAY 0.680851 (-4325 1400);
DISPLAY INVISIBLE (-4325 1400);
FORCEPROP 1 LASTPIN (-4375 1225) $PN 1
J 0
(-4363 1237);
DISPLAY 0.787234 (-4363 1237);
PAINT MONO (-4363 1237);
FORCEPROP 1 LASTPIN (-4175 1225) $PN 2
J 0
(-4213 1237);
DISPLAY 0.787234 (-4213 1237);
PAINT MONO (-4213 1237);
FORCEPROP 1 LAST MATERIAL EMPTY
J 0
(-4275 1075);
DISPLAY 0.978723 (-4275 1075);
PAINT RED (-4275 1075);
FORCEPROP 1 LAST PACK_TYPE 0402LF
J 0
(-4025 1075);
DISPLAY 0.978723 (-4025 1075);
FORCEPROP 1 LAST VALUE 10K
J 2
(-4300 1125);
DISPLAY 0.978723 (-4300 1125);
FORCEPROP 1 LAST TOLERANCE 1%
J 0
(-4275 1125);
DISPLAY 0.978723 (-4275 1125);
FORCEPROP 1 LAST WATTAGE 1/16W
J 2
(-4300 1075);
DISPLAY 0.978723 (-4300 1075);
FORCEPROP 2 LAST CDS_LIB pure_quanta
J 0
(-4275 1225);
DISPLAY INVISIBLE (-4275 1225);
FORCEPROP 1 LAST PATH I251
J 0
(-4325 1375);
DISPLAY 0.978723 (-4325 1375);
PAINT WHITE (-4325 1375);
DISPLAY INVISIBLE (-4325 1375);
FORCEPROP 1 LAST PART_NUMBER CS31002FB08
J 0
(-4325 1350);
DISPLAY 0.978723 (-4325 1350);
DISPLAY INVISIBLE (-4325 1350);
FORCEADD Q_RES..1
(-2425 750);
FORCEPROP 1 LAST LOCATION R8090
J 0
(-2475 800);
DISPLAY 0.978723 (-2475 800);
FORCEPROP 0 LAST $SEC 1
J 0
(-2475 850);
DISPLAY 0.680851 (-2475 850);
PAINT MONO (-2475 850);
DISPLAY INVISIBLE (-2475 850);
FORCEPROP 0 LAST CDS_SEC 1
J 0
(-2475 850);
DISPLAY 0.680851 (-2475 850);
DISPLAY INVISIBLE (-2475 850);
FORCEPROP 1 LASTPIN (-2525 750) $PN 1
J 0
(-2513 762);
DISPLAY 0.787234 (-2513 762);
PAINT MONO (-2513 762);
FORCEPROP 1 LASTPIN (-2325 750) $PN 2
J 0
(-2363 762);
DISPLAY 0.787234 (-2363 762);
PAINT MONO (-2363 762);
FORCEPROP 1 LAST WATTAGE 1/16W
J 2
(-2450 600);
DISPLAY 0.978723 (-2450 600);
FORCEPROP 1 LAST VALUE 0
J 2
(-2450 650);
DISPLAY 0.978723 (-2450 650);
FORCEPROP 1 LAST TOLERANCE 5%
J 0
(-2425 650);
DISPLAY 0.978723 (-2425 650);
FORCEPROP 1 LAST MATERIAL CHIP
J 0
(-2425 600);
DISPLAY 0.978723 (-2425 600);
FORCEPROP 1 LAST PACK_TYPE 0402LF
J 0
(-2175 600);
DISPLAY 0.978723 (-2175 600);
FORCEPROP 2 LAST CDS_LIB pure_quanta
J 0
(-2425 750);
DISPLAY INVISIBLE (-2425 750);
FORCEPROP 1 LAST PATH I252
J 0
(-2475 900);
DISPLAY 0.978723 (-2475 900);
PAINT WHITE (-2475 900);
DISPLAY INVISIBLE (-2475 900);
FORCEPROP 1 LAST PART_NUMBER CS00002JB13
J 0
(-2625 525);
DISPLAY 0.978723 (-2625 525);
DISPLAY INVISIBLE (-2625 525);
FORCEADD SCHOTTKY_12..1
(-2325 1200);
FORCEPROP 1 LAST LOCATION D8006
J 0
(-2400 1375);
DISPLAY 0.723404 (-2400 1375);
PAINT GREEN (-2400 1375);
FORCEPROP 0 LAST $SEC 1
J 0
(-2400 1525);
DISPLAY 0.680851 (-2400 1525);
PAINT MONO (-2400 1525);
DISPLAY INVISIBLE (-2400 1525);
FORCEPROP 0 LAST CDS_SEC 1
J 0
(-2400 1525);
DISPLAY 0.680851 (-2400 1525);
DISPLAY INVISIBLE (-2400 1525);
FORCEPROP 0 LASTPIN (-2450 1200) $PN 1
J 2
(-2460 1210);
DISPLAY 0.680851 (-2460 1210);
PAINT MONO (-2460 1210);
FORCEPROP 0 LASTPIN (-2200 1200) $PN 2
J 0
(-2190 1210);
DISPLAY 0.680851 (-2190 1210);
PAINT MONO (-2190 1210);
FORCEPROP 1 LAST MATERIAL EMPTY
J 0
(-2400 1275);
DISPLAY 0.723404 (-2400 1275);
PAINT RED (-2400 1275);
FORCEPROP 2 LAST PART_TYPE SMLF
J 0
(-2400 1475);
DISPLAY 0.680851 (-2400 1475);
FORCEPROP 2 LAST VALUE B0530WS7F
J 0
(-2400 1425);
DISPLAY 0.680851 (-2400 1425);
FORCEPROP 2 LAST CDS_LIB pure_quanta
J 0
(-2325 1200);
DISPLAY INVISIBLE (-2325 1200);
FORCEPROP 1 LAST CDS_LMAN_SYM_OUTLINE -75,50,75,-50
J 0
(-2325 1200);
DISPLAY 0.468085 (-2325 1200);
PAINT GREEN (-2325 1200);
DISPLAY INVISIBLE (-2325 1200);
FORCEPROP 1 LAST NEEDS_NO_SIZE TRUE
J 0
(-2250 1150);
DISPLAY 0.468085 (-2250 1150);
PAINT GREEN (-2250 1150);
DISPLAY INVISIBLE (-2250 1150);
FORCEPROP 1 LAST PATH I253
J 0
(-2325 1200);
DISPLAY 0.723404 (-2325 1200);
PAINT GREEN (-2325 1200);
DISPLAY INVISIBLE (-2325 1200);
FORCEPROP 1 LAST PART_NUMBER BC000530Z41
J 0
(-2400 1325);
DISPLAY 0.723404 (-2400 1325);
PAINT GREEN (-2400 1325);
DISPLAY INVISIBLE (-2400 1325);
FORCEADD OFFPAGE..6
R 2
(-1225 750);
FORCEPROP 2 LAST $XR0 82 
J 0
(-1011 750);
DISPLAY 0.638298 (-1011 750);
PAINT MONO (-1011 750);
FORCEPROP 2 LAST CDS_LIB standard
J 0
(-1225 750);
DISPLAY INVISIBLE (-1225 750);
FORCEPROP 1 LAST OFFPAGE TRUE
J 2
(-1550 625);
DISPLAY 0.872340 (-1550 625);
PAINT GREEN (-1550 625);
DISPLAY INVISIBLE (-1550 625);
FORCEPROP 1 LAST COMMENT_BODY TRUE
J 2
(-1325 675);
DISPLAY 0.872340 (-1325 675);
PAINT GREEN (-1325 675);
DISPLAY INVISIBLE (-1325 675);
FORCEPROP 2 LAST PATH I254
J 0
(-1025 825);
DISPLAY 0.680851 (-1025 825);
DISPLAY INVISIBLE (-1025 825);
FORCEADD VCC_CORE..1
(-1650 1325);
FORCEPROP 3 LASTPIN (-1650 1275) SIG_NAME P3V3_AUX\g
J 0
(-1640 1285);
DISPLAY 0.659574 (-1640 1285);
PAINT MONO (-1640 1285);
DISPLAY INVISIBLE (-1640 1285);
FORCEPROP 1 LAST HDL_POWER P3V3_AUX
J 1
(-1650 1375);
DISPLAY 0.489362 (-1650 1375);
PAINT GREEN (-1650 1375);
FORCEPROP 2 LAST CDS_LIB pure_quanta_power
J 0
(-1650 1325);
DISPLAY INVISIBLE (-1650 1325);
FORCEPROP 2 LAST ROOM PVCCINFAON_CPU0_CTRL
J 0
(-1650 1425);
DISPLAY 0.808511 (-1650 1425);
PAINT RED (-1650 1425);
DISPLAY INVISIBLE (-1650 1425);
FORCEPROP 0 LAST VOLTAGE 3.3
J 0
(-1925 1475);
DISPLAY 1.021277 (-1925 1475);
PAINT SKYBLUE (-1925 1475);
DISPLAY INVISIBLE (-1925 1475);
FORCEPROP 1 LAST PATH I255
J 0
(-1600 1350);
DISPLAY 0.872340 (-1600 1350);
PAINT AQUA (-1600 1350);
DISPLAY INVISIBLE (-1600 1350);
FORCEADD Q_RES..1
(-7900 2800);
FORCEPROP 1 LAST LOCATION R1705
J 0
(-8075 2800);
DISPLAY 0.638298 (-8075 2800);
FORCEPROP 0 LAST $SEC 1
J 0
(-8075 2850);
DISPLAY 0.680851 (-8075 2850);
PAINT MONO (-8075 2850);
DISPLAY INVISIBLE (-8075 2850);
FORCEPROP 0 LAST CDS_SEC 1
J 0
(-8075 2850);
DISPLAY 0.680851 (-8075 2850);
DISPLAY INVISIBLE (-8075 2850);
FORCEPROP 1 LASTPIN (-8000 2800) $PN 1
J 0
(-7988 2812);
DISPLAY 0.787234 (-7988 2812);
PAINT MONO (-7988 2812);
FORCEPROP 1 LASTPIN (-7800 2800) $PN 2
J 0
(-7838 2812);
DISPLAY 0.787234 (-7838 2812);
PAINT MONO (-7838 2812);
FORCEPROP 1 LAST VALUE 10
J 2
(-7750 2800);
DISPLAY 0.404255 (-7750 2800);
FORCEPROP 1 LAST MATERIAL CHIP
J 0
(-8000 2775);
DISPLAY 0.404255 (-8000 2775);
FORCEPROP 1 LAST PACK_TYPE 0402LF
J 0
(-7850 2775);
DISPLAY 0.404255 (-7850 2775);
FORCEPROP 2 LAST CDS_LIB pure_quanta
J 0
(-7900 2800);
DISPLAY INVISIBLE (-7900 2800);
FORCEPROP 1 LAST WATTAGE 1/16W
J 2
(-7925 2650);
DISPLAY 0.978723 (-7925 2650);
DISPLAY INVISIBLE (-7925 2650);
FORCEPROP 1 LAST TOLERANCE 1%
J 0
(-7900 2700);
DISPLAY 0.978723 (-7900 2700);
DISPLAY INVISIBLE (-7900 2700);
FORCEPROP 1 LAST PATH I256
J 0
(-7950 2950);
DISPLAY 0.978723 (-7950 2950);
PAINT WHITE (-7950 2950);
DISPLAY INVISIBLE (-7950 2950);
FORCEPROP 1 LAST PART_NUMBER CS01002FB07
J 0
(-7950 2900);
DISPLAY 0.978723 (-7950 2900);
DISPLAY INVISIBLE (-7950 2900);
FORCEADD OFFPAGE..6
(-8600 2700);
FORCEPROP 2 LAST $XR5 159 
J 0
(-9030 2664);
DISPLAY 0.638298 (-9030 2664);
PAINT MONO (-9030 2664);
FORCEPROP 2 LAST $XR4 109 
J 0
(-8910 2664);
DISPLAY 0.638298 (-8910 2664);
PAINT MONO (-8910 2664);
FORCEPROP 2 LAST $XR3 108 
J 0
(-9270 2700);
DISPLAY 0.638298 (-9270 2700);
PAINT MONO (-9270 2700);
FORCEPROP 2 LAST $XR2 107 
J 0
(-9150 2700);
DISPLAY 0.638298 (-9150 2700);
PAINT MONO (-9150 2700);
FORCEPROP 2 LAST $XR1 106 
J 0
(-9030 2700);
DISPLAY 0.638298 (-9030 2700);
PAINT MONO (-9030 2700);
FORCEPROP 2 LAST $XR0 105 
J 0
(-8910 2700);
DISPLAY 0.638298 (-8910 2700);
PAINT MONO (-8910 2700);
FORCEPROP 2 LAST CDS_LIB mstr_standard
J 0
(-8600 2700);
DISPLAY 0.808511 (-8600 2700);
DISPLAY INVISIBLE (-8600 2700);
FORCEPROP 1 LAST OFFPAGE TRUE
J 0
(-8275 2575);
DISPLAY 0.872340 (-8275 2575);
PAINT GREEN (-8275 2575);
DISPLAY INVISIBLE (-8275 2575);
FORCEPROP 1 LAST COMMENT_BODY TRUE
J 0
(-8500 2625);
DISPLAY 0.872340 (-8500 2625);
PAINT GREEN (-8500 2625);
DISPLAY INVISIBLE (-8500 2625);
FORCEPROP 2 LAST PATH I257
J 0
(-8875 2750);
DISPLAY 0.680851 (-8875 2750);
DISPLAY INVISIBLE (-8875 2750);
FORCEADD TAP..1
R 2
(-7475 3300);
FORCEPROP 3 LASTPIN (-7425 3300) SIG_NAME M_G_CPU1_SB_CB<3>
J 0
(-7415 3310);
DISPLAY 0.659574 (-7415 3310);
PAINT MONO (-7415 3310);
DISPLAY INVISIBLE (-7415 3310);
FORCEPROP 1 LASTPIN (-7425 3300) BN 3
J 2
(-7413 3308);
DISPLAY 0.489362 (-7413 3308);
PAINT GREEN (-7413 3308);
FORCEPROP 2 LAST CDS_LIB mstr_standard
J 0
(-7475 3300);
DISPLAY 0.723404 (-7475 3300);
PAINT MONO (-7475 3300);
DISPLAY INVISIBLE (-7475 3300);
FORCEPROP 1 LAST BODY_TYPE PLUMBING
J 2
(-7475 3350);
DISPLAY 0.872340 (-7475 3350);
PAINT GREEN (-7475 3350);
DISPLAY INVISIBLE (-7475 3350);
FORCEPROP 1 LAST HDL_TAP TRUE
J 2
(-7800 3175);
DISPLAY 0.872340 (-7800 3175);
DISPLAY INVISIBLE (-7800 3175);
FORCEPROP 1 LAST PATH I26
J 2
(-7473 3300);
DISPLAY 0.872340 (-7473 3300);
PAINT GREEN (-7473 3300);
DISPLAY INVISIBLE (-7473 3300);
FORCEADD TAP..1
R 2
(-7475 3250);
FORCEPROP 3 LASTPIN (-7425 3250) SIG_NAME M_G_CPU1_SB_CB<2>
J 0
(-7415 3260);
DISPLAY 0.659574 (-7415 3260);
PAINT MONO (-7415 3260);
DISPLAY INVISIBLE (-7415 3260);
FORCEPROP 1 LASTPIN (-7425 3250) BN 2
J 2
(-7413 3258);
DISPLAY 0.489362 (-7413 3258);
PAINT GREEN (-7413 3258);
FORCEPROP 2 LAST CDS_LIB mstr_standard
J 0
(-7475 3250);
DISPLAY 0.723404 (-7475 3250);
PAINT MONO (-7475 3250);
DISPLAY INVISIBLE (-7475 3250);
FORCEPROP 1 LAST BODY_TYPE PLUMBING
J 2
(-7475 3300);
DISPLAY 0.872340 (-7475 3300);
PAINT GREEN (-7475 3300);
DISPLAY INVISIBLE (-7475 3300);
FORCEPROP 1 LAST HDL_TAP TRUE
J 2
(-7800 3125);
DISPLAY 0.872340 (-7800 3125);
DISPLAY INVISIBLE (-7800 3125);
FORCEPROP 1 LAST PATH I27
J 2
(-7473 3250);
DISPLAY 0.872340 (-7473 3250);
PAINT GREEN (-7473 3250);
DISPLAY INVISIBLE (-7473 3250);
FORCEADD TAP..1
R 2
(-7475 3400);
FORCEPROP 3 LASTPIN (-7425 3400) SIG_NAME M_G_CPU1_SB_CB<5>
J 0
(-7415 3410);
DISPLAY 0.659574 (-7415 3410);
PAINT MONO (-7415 3410);
DISPLAY INVISIBLE (-7415 3410);
FORCEPROP 1 LASTPIN (-7425 3400) BN 5
J 2
(-7413 3408);
DISPLAY 0.489362 (-7413 3408);
PAINT GREEN (-7413 3408);
FORCEPROP 2 LAST CDS_LIB mstr_standard
J 0
(-7475 3400);
DISPLAY 0.723404 (-7475 3400);
PAINT MONO (-7475 3400);
DISPLAY INVISIBLE (-7475 3400);
FORCEPROP 1 LAST BODY_TYPE PLUMBING
J 2
(-7475 3450);
DISPLAY 0.872340 (-7475 3450);
PAINT GREEN (-7475 3450);
DISPLAY INVISIBLE (-7475 3450);
FORCEPROP 1 LAST HDL_TAP TRUE
J 2
(-7800 3275);
DISPLAY 0.872340 (-7800 3275);
DISPLAY INVISIBLE (-7800 3275);
FORCEPROP 1 LAST PATH I28
J 2
(-7473 3400);
DISPLAY 0.872340 (-7473 3400);
PAINT GREEN (-7473 3400);
DISPLAY INVISIBLE (-7473 3400);
FORCEADD TAP..1
R 2
(-7475 3450);
FORCEPROP 3 LASTPIN (-7425 3450) SIG_NAME M_G_CPU1_SB_CB<6>
J 0
(-7415 3460);
DISPLAY 0.659574 (-7415 3460);
PAINT MONO (-7415 3460);
DISPLAY INVISIBLE (-7415 3460);
FORCEPROP 1 LASTPIN (-7425 3450) BN 6
J 2
(-7413 3458);
DISPLAY 0.489362 (-7413 3458);
PAINT GREEN (-7413 3458);
FORCEPROP 2 LAST CDS_LIB mstr_standard
J 0
(-7475 3450);
DISPLAY 0.723404 (-7475 3450);
PAINT MONO (-7475 3450);
DISPLAY INVISIBLE (-7475 3450);
FORCEPROP 1 LAST BODY_TYPE PLUMBING
J 2
(-7475 3500);
DISPLAY 0.872340 (-7475 3500);
PAINT GREEN (-7475 3500);
DISPLAY INVISIBLE (-7475 3500);
FORCEPROP 1 LAST HDL_TAP TRUE
J 2
(-7800 3325);
DISPLAY 0.872340 (-7800 3325);
DISPLAY INVISIBLE (-7800 3325);
FORCEPROP 1 LAST PATH I29
J 2
(-7473 3450);
DISPLAY 0.872340 (-7473 3450);
PAINT GREEN (-7473 3450);
DISPLAY INVISIBLE (-7473 3450);
FORCEADD TAP..1
R 2
(-7475 3650);
FORCEPROP 3 LASTPIN (-7425 3650) SIG_NAME M_G_CPU1_SA_CB<1>
J 0
(-7415 3660);
DISPLAY 0.659574 (-7415 3660);
PAINT MONO (-7415 3660);
DISPLAY INVISIBLE (-7415 3660);
FORCEPROP 1 LASTPIN (-7425 3650) BN 1
J 2
(-7413 3658);
DISPLAY 0.489362 (-7413 3658);
PAINT GREEN (-7413 3658);
FORCEPROP 2 LAST CDS_LIB mstr_standard
J 0
(-7475 3650);
DISPLAY 0.723404 (-7475 3650);
PAINT MONO (-7475 3650);
DISPLAY INVISIBLE (-7475 3650);
FORCEPROP 1 LAST BODY_TYPE PLUMBING
J 2
(-7475 3700);
DISPLAY 0.872340 (-7475 3700);
PAINT GREEN (-7475 3700);
DISPLAY INVISIBLE (-7475 3700);
FORCEPROP 1 LAST HDL_TAP TRUE
J 2
(-7800 3525);
DISPLAY 0.872340 (-7800 3525);
DISPLAY INVISIBLE (-7800 3525);
FORCEPROP 1 LAST PATH I30
J 2
(-7473 3650);
DISPLAY 0.872340 (-7473 3650);
PAINT GREEN (-7473 3650);
DISPLAY INVISIBLE (-7473 3650);
FORCEADD TAP..1
R 2
(-7475 3700);
FORCEPROP 3 LASTPIN (-7425 3700) SIG_NAME M_G_CPU1_SA_CB<2>
J 0
(-7415 3710);
DISPLAY 0.659574 (-7415 3710);
PAINT MONO (-7415 3710);
DISPLAY INVISIBLE (-7415 3710);
FORCEPROP 1 LASTPIN (-7425 3700) BN 2
J 2
(-7413 3708);
DISPLAY 0.489362 (-7413 3708);
PAINT GREEN (-7413 3708);
FORCEPROP 2 LAST CDS_LIB mstr_standard
J 0
(-7475 3700);
DISPLAY 0.723404 (-7475 3700);
PAINT MONO (-7475 3700);
DISPLAY INVISIBLE (-7475 3700);
FORCEPROP 1 LAST BODY_TYPE PLUMBING
J 2
(-7475 3750);
DISPLAY 0.872340 (-7475 3750);
PAINT GREEN (-7475 3750);
DISPLAY INVISIBLE (-7475 3750);
FORCEPROP 1 LAST HDL_TAP TRUE
J 2
(-7800 3575);
DISPLAY 0.872340 (-7800 3575);
DISPLAY INVISIBLE (-7800 3575);
FORCEPROP 1 LAST PATH I31
J 2
(-7473 3700);
DISPLAY 0.872340 (-7473 3700);
PAINT GREEN (-7473 3700);
DISPLAY INVISIBLE (-7473 3700);
FORCEADD TAP..1
R 2
(-7475 3500);
FORCEPROP 3 LASTPIN (-7425 3500) SIG_NAME M_G_CPU1_SB_CB<7>
J 0
(-7415 3510);
DISPLAY 0.659574 (-7415 3510);
PAINT MONO (-7415 3510);
DISPLAY INVISIBLE (-7415 3510);
FORCEPROP 1 LASTPIN (-7425 3500) BN 7
J 2
(-7413 3508);
DISPLAY 0.489362 (-7413 3508);
PAINT GREEN (-7413 3508);
FORCEPROP 2 LAST CDS_LIB mstr_standard
J 0
(-7475 3500);
DISPLAY 0.723404 (-7475 3500);
PAINT MONO (-7475 3500);
DISPLAY INVISIBLE (-7475 3500);
FORCEPROP 1 LAST BODY_TYPE PLUMBING
J 2
(-7475 3550);
DISPLAY 0.872340 (-7475 3550);
PAINT GREEN (-7475 3550);
DISPLAY INVISIBLE (-7475 3550);
FORCEPROP 1 LAST HDL_TAP TRUE
J 2
(-7800 3375);
DISPLAY 0.872340 (-7800 3375);
DISPLAY INVISIBLE (-7800 3375);
FORCEPROP 1 LAST PATH I32
J 2
(-7473 3500);
DISPLAY 0.872340 (-7473 3500);
PAINT GREEN (-7473 3500);
DISPLAY INVISIBLE (-7473 3500);
FORCEADD TAP..1
R 2
(-7475 3600);
FORCEPROP 3 LASTPIN (-7425 3600) SIG_NAME M_G_CPU1_SA_CB<0>
J 0
(-7415 3610);
DISPLAY 0.659574 (-7415 3610);
PAINT MONO (-7415 3610);
DISPLAY INVISIBLE (-7415 3610);
FORCEPROP 1 LASTPIN (-7425 3600) BN 0
J 2
(-7413 3608);
DISPLAY 0.489362 (-7413 3608);
PAINT GREEN (-7413 3608);
FORCEPROP 2 LAST CDS_LIB mstr_standard
J 0
(-7475 3600);
DISPLAY 0.723404 (-7475 3600);
PAINT MONO (-7475 3600);
DISPLAY INVISIBLE (-7475 3600);
FORCEPROP 1 LAST BODY_TYPE PLUMBING
J 2
(-7475 3650);
DISPLAY 0.872340 (-7475 3650);
PAINT GREEN (-7475 3650);
DISPLAY INVISIBLE (-7475 3650);
FORCEPROP 1 LAST HDL_TAP TRUE
J 2
(-7800 3475);
DISPLAY 0.872340 (-7800 3475);
DISPLAY INVISIBLE (-7800 3475);
FORCEPROP 1 LAST PATH I33
J 2
(-7473 3600);
DISPLAY 0.872340 (-7473 3600);
PAINT GREEN (-7473 3600);
DISPLAY INVISIBLE (-7473 3600);
FORCEADD TAP..1
R 2
(-7475 3750);
FORCEPROP 3 LASTPIN (-7425 3750) SIG_NAME M_G_CPU1_SA_CB<3>
J 0
(-7415 3760);
DISPLAY 0.659574 (-7415 3760);
PAINT MONO (-7415 3760);
DISPLAY INVISIBLE (-7415 3760);
FORCEPROP 1 LASTPIN (-7425 3750) BN 3
J 2
(-7413 3758);
DISPLAY 0.489362 (-7413 3758);
PAINT GREEN (-7413 3758);
FORCEPROP 2 LAST CDS_LIB mstr_standard
J 0
(-7475 3750);
DISPLAY 0.723404 (-7475 3750);
PAINT MONO (-7475 3750);
DISPLAY INVISIBLE (-7475 3750);
FORCEPROP 1 LAST BODY_TYPE PLUMBING
J 2
(-7475 3800);
DISPLAY 0.872340 (-7475 3800);
PAINT GREEN (-7475 3800);
DISPLAY INVISIBLE (-7475 3800);
FORCEPROP 1 LAST HDL_TAP TRUE
J 2
(-7800 3625);
DISPLAY 0.872340 (-7800 3625);
DISPLAY INVISIBLE (-7800 3625);
FORCEPROP 1 LAST PATH I34
J 2
(-7473 3750);
DISPLAY 0.872340 (-7473 3750);
PAINT GREEN (-7473 3750);
DISPLAY INVISIBLE (-7473 3750);
FORCEADD TAP..1
(-5775 2200);
FORCEPROP 3 LASTPIN (-5825 2200) SIG_NAME M_G_CPU1_SB_DQ<1>
J 0
(-5815 2210);
DISPLAY 0.659574 (-5815 2210);
PAINT MONO (-5815 2210);
DISPLAY INVISIBLE (-5815 2210);
FORCEPROP 1 LASTPIN (-5825 2200) BN 1
J 0
(-5837 2208);
DISPLAY 0.489362 (-5837 2208);
PAINT GREEN (-5837 2208);
FORCEPROP 2 LAST CDS_LIB mstr_standard
J 0
(-5775 2200);
DISPLAY 0.723404 (-5775 2200);
PAINT MONO (-5775 2200);
DISPLAY INVISIBLE (-5775 2200);
FORCEPROP 1 LAST BODY_TYPE PLUMBING
J 0
(-5775 2250);
DISPLAY 0.872340 (-5775 2250);
PAINT GREEN (-5775 2250);
DISPLAY INVISIBLE (-5775 2250);
FORCEPROP 1 LAST HDL_TAP TRUE
J 0
(-5450 2075);
DISPLAY 0.872340 (-5450 2075);
DISPLAY INVISIBLE (-5450 2075);
FORCEPROP 1 LAST PATH I42
J 0
(-5777 2200);
DISPLAY 0.872340 (-5777 2200);
PAINT GREEN (-5777 2200);
DISPLAY INVISIBLE (-5777 2200);
FORCEADD TAP..1
(-5775 2150);
FORCEPROP 3 LASTPIN (-5825 2150) SIG_NAME M_G_CPU1_SB_DQ<0>
J 0
(-5815 2160);
DISPLAY 0.659574 (-5815 2160);
PAINT MONO (-5815 2160);
DISPLAY INVISIBLE (-5815 2160);
FORCEPROP 1 LASTPIN (-5825 2150) BN 0
J 0
(-5837 2158);
DISPLAY 0.489362 (-5837 2158);
PAINT GREEN (-5837 2158);
FORCEPROP 2 LAST CDS_LIB mstr_standard
J 0
(-5775 2150);
DISPLAY 0.723404 (-5775 2150);
PAINT MONO (-5775 2150);
DISPLAY INVISIBLE (-5775 2150);
FORCEPROP 1 LAST BODY_TYPE PLUMBING
J 0
(-5775 2200);
DISPLAY 0.872340 (-5775 2200);
PAINT GREEN (-5775 2200);
DISPLAY INVISIBLE (-5775 2200);
FORCEPROP 1 LAST HDL_TAP TRUE
J 0
(-5450 2025);
DISPLAY 0.872340 (-5450 2025);
DISPLAY INVISIBLE (-5450 2025);
FORCEPROP 1 LAST PATH I43
J 0
(-5777 2150);
DISPLAY 0.872340 (-5777 2150);
PAINT GREEN (-5777 2150);
DISPLAY INVISIBLE (-5777 2150);
FORCEADD TAP..1
(-5775 2400);
FORCEPROP 3 LASTPIN (-5825 2400) SIG_NAME M_G_CPU1_SB_DQ<5>
J 0
(-5815 2410);
DISPLAY 0.659574 (-5815 2410);
PAINT MONO (-5815 2410);
DISPLAY INVISIBLE (-5815 2410);
FORCEPROP 1 LASTPIN (-5825 2400) BN 5
J 0
(-5837 2408);
DISPLAY 0.489362 (-5837 2408);
PAINT GREEN (-5837 2408);
FORCEPROP 2 LAST CDS_LIB mstr_standard
J 0
(-5775 2400);
DISPLAY 0.723404 (-5775 2400);
PAINT MONO (-5775 2400);
DISPLAY INVISIBLE (-5775 2400);
FORCEPROP 1 LAST BODY_TYPE PLUMBING
J 0
(-5775 2450);
DISPLAY 0.872340 (-5775 2450);
PAINT GREEN (-5775 2450);
DISPLAY INVISIBLE (-5775 2450);
FORCEPROP 1 LAST HDL_TAP TRUE
J 0
(-5450 2275);
DISPLAY 0.872340 (-5450 2275);
DISPLAY INVISIBLE (-5450 2275);
FORCEPROP 1 LAST PATH I44
J 0
(-5777 2400);
DISPLAY 0.872340 (-5777 2400);
PAINT GREEN (-5777 2400);
DISPLAY INVISIBLE (-5777 2400);
FORCEADD TAP..1
(-5775 2450);
FORCEPROP 3 LASTPIN (-5825 2450) SIG_NAME M_G_CPU1_SB_DQ<6>
J 0
(-5815 2460);
DISPLAY 0.659574 (-5815 2460);
PAINT MONO (-5815 2460);
DISPLAY INVISIBLE (-5815 2460);
FORCEPROP 1 LASTPIN (-5825 2450) BN 6
J 0
(-5837 2458);
DISPLAY 0.489362 (-5837 2458);
PAINT GREEN (-5837 2458);
FORCEPROP 2 LAST CDS_LIB mstr_standard
J 0
(-5775 2450);
DISPLAY 0.723404 (-5775 2450);
PAINT MONO (-5775 2450);
DISPLAY INVISIBLE (-5775 2450);
FORCEPROP 1 LAST BODY_TYPE PLUMBING
J 0
(-5775 2500);
DISPLAY 0.872340 (-5775 2500);
PAINT GREEN (-5775 2500);
DISPLAY INVISIBLE (-5775 2500);
FORCEPROP 1 LAST HDL_TAP TRUE
J 0
(-5450 2325);
DISPLAY 0.872340 (-5450 2325);
DISPLAY INVISIBLE (-5450 2325);
FORCEPROP 1 LAST PATH I45
J 0
(-5777 2450);
DISPLAY 0.872340 (-5777 2450);
PAINT GREEN (-5777 2450);
DISPLAY INVISIBLE (-5777 2450);
FORCEADD TAP..1
(-5775 2250);
FORCEPROP 3 LASTPIN (-5825 2250) SIG_NAME M_G_CPU1_SB_DQ<2>
J 0
(-5815 2260);
DISPLAY 0.659574 (-5815 2260);
PAINT MONO (-5815 2260);
DISPLAY INVISIBLE (-5815 2260);
FORCEPROP 1 LASTPIN (-5825 2250) BN 2
J 0
(-5837 2258);
DISPLAY 0.489362 (-5837 2258);
PAINT GREEN (-5837 2258);
FORCEPROP 2 LAST CDS_LIB mstr_standard
J 0
(-5775 2250);
DISPLAY 0.723404 (-5775 2250);
PAINT MONO (-5775 2250);
DISPLAY INVISIBLE (-5775 2250);
FORCEPROP 1 LAST BODY_TYPE PLUMBING
J 0
(-5775 2300);
DISPLAY 0.872340 (-5775 2300);
PAINT GREEN (-5775 2300);
DISPLAY INVISIBLE (-5775 2300);
FORCEPROP 1 LAST HDL_TAP TRUE
J 0
(-5450 2125);
DISPLAY 0.872340 (-5450 2125);
DISPLAY INVISIBLE (-5450 2125);
FORCEPROP 1 LAST PATH I46
J 0
(-5777 2250);
DISPLAY 0.872340 (-5777 2250);
PAINT GREEN (-5777 2250);
DISPLAY INVISIBLE (-5777 2250);
FORCEADD TAP..1
(-5775 2300);
FORCEPROP 3 LASTPIN (-5825 2300) SIG_NAME M_G_CPU1_SB_DQ<3>
J 0
(-5815 2310);
DISPLAY 0.659574 (-5815 2310);
PAINT MONO (-5815 2310);
DISPLAY INVISIBLE (-5815 2310);
FORCEPROP 1 LASTPIN (-5825 2300) BN 3
J 0
(-5837 2308);
DISPLAY 0.489362 (-5837 2308);
PAINT GREEN (-5837 2308);
FORCEPROP 2 LAST CDS_LIB mstr_standard
J 0
(-5775 2300);
DISPLAY 0.723404 (-5775 2300);
PAINT MONO (-5775 2300);
DISPLAY INVISIBLE (-5775 2300);
FORCEPROP 1 LAST BODY_TYPE PLUMBING
J 0
(-5775 2350);
DISPLAY 0.872340 (-5775 2350);
PAINT GREEN (-5775 2350);
DISPLAY INVISIBLE (-5775 2350);
FORCEPROP 1 LAST HDL_TAP TRUE
J 0
(-5450 2175);
DISPLAY 0.872340 (-5450 2175);
DISPLAY INVISIBLE (-5450 2175);
FORCEPROP 1 LAST PATH I47
J 0
(-5777 2300);
DISPLAY 0.872340 (-5777 2300);
PAINT GREEN (-5777 2300);
DISPLAY INVISIBLE (-5777 2300);
FORCEADD TAP..1
(-5775 2350);
FORCEPROP 3 LASTPIN (-5825 2350) SIG_NAME M_G_CPU1_SB_DQ<4>
J 0
(-5815 2360);
DISPLAY 0.659574 (-5815 2360);
PAINT MONO (-5815 2360);
DISPLAY INVISIBLE (-5815 2360);
FORCEPROP 1 LASTPIN (-5825 2350) BN 4
J 0
(-5837 2358);
DISPLAY 0.489362 (-5837 2358);
PAINT GREEN (-5837 2358);
FORCEPROP 2 LAST CDS_LIB mstr_standard
J 0
(-5775 2350);
DISPLAY 0.723404 (-5775 2350);
PAINT MONO (-5775 2350);
DISPLAY INVISIBLE (-5775 2350);
FORCEPROP 1 LAST BODY_TYPE PLUMBING
J 0
(-5775 2400);
DISPLAY 0.872340 (-5775 2400);
PAINT GREEN (-5775 2400);
DISPLAY INVISIBLE (-5775 2400);
FORCEPROP 1 LAST HDL_TAP TRUE
J 0
(-5450 2225);
DISPLAY 0.872340 (-5450 2225);
DISPLAY INVISIBLE (-5450 2225);
FORCEPROP 1 LAST PATH I48
J 0
(-5777 2350);
DISPLAY 0.872340 (-5777 2350);
PAINT GREEN (-5777 2350);
DISPLAY INVISIBLE (-5777 2350);
FORCEADD TAP..1
(-5775 2650);
FORCEPROP 3 LASTPIN (-5825 2650) SIG_NAME M_G_CPU1_SB_DQ<10>
J 0
(-5815 2660);
DISPLAY 0.659574 (-5815 2660);
PAINT MONO (-5815 2660);
DISPLAY INVISIBLE (-5815 2660);
FORCEPROP 1 LASTPIN (-5825 2650) BN 10
J 0
(-5837 2658);
DISPLAY 0.489362 (-5837 2658);
PAINT GREEN (-5837 2658);
FORCEPROP 2 LAST CDS_LIB mstr_standard
J 0
(-5775 2650);
DISPLAY 0.723404 (-5775 2650);
PAINT MONO (-5775 2650);
DISPLAY INVISIBLE (-5775 2650);
FORCEPROP 1 LAST BODY_TYPE PLUMBING
J 0
(-5775 2700);
DISPLAY 0.872340 (-5775 2700);
PAINT GREEN (-5775 2700);
DISPLAY INVISIBLE (-5775 2700);
FORCEPROP 1 LAST HDL_TAP TRUE
J 0
(-5450 2525);
DISPLAY 0.872340 (-5450 2525);
DISPLAY INVISIBLE (-5450 2525);
FORCEPROP 1 LAST PATH I49
J 0
(-5777 2650);
DISPLAY 0.872340 (-5777 2650);
PAINT GREEN (-5777 2650);
DISPLAY INVISIBLE (-5777 2650);
FORCEADD VCC_CORE..1
(-8575 3425);
FORCEPROP 3 LASTPIN (-8575 3375) SIG_NAME P3V3_AUX\g
J 0
(-8565 3385);
DISPLAY 0.659574 (-8565 3385);
PAINT MONO (-8565 3385);
DISPLAY INVISIBLE (-8565 3385);
FORCEPROP 1 LAST HDL_POWER P3V3_AUX
J 1
(-8575 3475);
DISPLAY 0.489362 (-8575 3475);
PAINT GREEN (-8575 3475);
FORCEPROP 2 LAST ROOM PVCCINFAON_CPU1_CTRL
J 0
(-8575 3525);
DISPLAY 0.808511 (-8575 3525);
PAINT RED (-8575 3525);
DISPLAY INVISIBLE (-8575 3525);
FORCEPROP 0 LAST VOLTAGE 3.3
J 0
(-8850 3575);
DISPLAY 1.021277 (-8850 3575);
PAINT SKYBLUE (-8850 3575);
DISPLAY INVISIBLE (-8850 3575);
FORCEPROP 2 LAST CDS_LIB mstr_symbols
J 0
(-8575 3425);
PAINT MONO (-8575 3425);
DISPLAY INVISIBLE (-8575 3425);
FORCEPROP 1 LAST PATH I5
J 0
(-8525 3450);
DISPLAY 0.872340 (-8525 3450);
PAINT AQUA (-8525 3450);
DISPLAY INVISIBLE (-8525 3450);
FORCEADD TAP..1
(-5775 2700);
FORCEPROP 3 LASTPIN (-5825 2700) SIG_NAME M_G_CPU1_SB_DQ<11>
J 0
(-5815 2710);
DISPLAY 0.659574 (-5815 2710);
PAINT MONO (-5815 2710);
DISPLAY INVISIBLE (-5815 2710);
FORCEPROP 1 LASTPIN (-5825 2700) BN 11
J 0
(-5837 2708);
DISPLAY 0.489362 (-5837 2708);
PAINT GREEN (-5837 2708);
FORCEPROP 2 LAST CDS_LIB mstr_standard
J 0
(-5775 2700);
DISPLAY 0.723404 (-5775 2700);
PAINT MONO (-5775 2700);
DISPLAY INVISIBLE (-5775 2700);
FORCEPROP 1 LAST BODY_TYPE PLUMBING
J 0
(-5775 2750);
DISPLAY 0.872340 (-5775 2750);
PAINT GREEN (-5775 2750);
DISPLAY INVISIBLE (-5775 2750);
FORCEPROP 1 LAST HDL_TAP TRUE
J 0
(-5450 2575);
DISPLAY 0.872340 (-5450 2575);
DISPLAY INVISIBLE (-5450 2575);
FORCEPROP 1 LAST PATH I50
J 0
(-5777 2700);
DISPLAY 0.872340 (-5777 2700);
PAINT GREEN (-5777 2700);
DISPLAY INVISIBLE (-5777 2700);
FORCEADD TAP..1
(-5775 2500);
FORCEPROP 3 LASTPIN (-5825 2500) SIG_NAME M_G_CPU1_SB_DQ<7>
J 0
(-5815 2510);
DISPLAY 0.659574 (-5815 2510);
PAINT MONO (-5815 2510);
DISPLAY INVISIBLE (-5815 2510);
FORCEPROP 1 LASTPIN (-5825 2500) BN 7
J 0
(-5837 2508);
DISPLAY 0.489362 (-5837 2508);
PAINT GREEN (-5837 2508);
FORCEPROP 2 LAST CDS_LIB mstr_standard
J 0
(-5775 2500);
DISPLAY 0.723404 (-5775 2500);
PAINT MONO (-5775 2500);
DISPLAY INVISIBLE (-5775 2500);
FORCEPROP 1 LAST BODY_TYPE PLUMBING
J 0
(-5775 2550);
DISPLAY 0.872340 (-5775 2550);
PAINT GREEN (-5775 2550);
DISPLAY INVISIBLE (-5775 2550);
FORCEPROP 1 LAST HDL_TAP TRUE
J 0
(-5450 2375);
DISPLAY 0.872340 (-5450 2375);
DISPLAY INVISIBLE (-5450 2375);
FORCEPROP 1 LAST PATH I51
J 0
(-5777 2500);
DISPLAY 0.872340 (-5777 2500);
PAINT GREEN (-5777 2500);
DISPLAY INVISIBLE (-5777 2500);
FORCEADD TAP..1
(-5775 2550);
FORCEPROP 3 LASTPIN (-5825 2550) SIG_NAME M_G_CPU1_SB_DQ<8>
J 0
(-5815 2560);
DISPLAY 0.659574 (-5815 2560);
PAINT MONO (-5815 2560);
DISPLAY INVISIBLE (-5815 2560);
FORCEPROP 1 LASTPIN (-5825 2550) BN 8
J 0
(-5837 2558);
DISPLAY 0.489362 (-5837 2558);
PAINT GREEN (-5837 2558);
FORCEPROP 2 LAST CDS_LIB mstr_standard
J 0
(-5775 2550);
DISPLAY 0.723404 (-5775 2550);
PAINT MONO (-5775 2550);
DISPLAY INVISIBLE (-5775 2550);
FORCEPROP 1 LAST BODY_TYPE PLUMBING
J 0
(-5775 2600);
DISPLAY 0.872340 (-5775 2600);
PAINT GREEN (-5775 2600);
DISPLAY INVISIBLE (-5775 2600);
FORCEPROP 1 LAST HDL_TAP TRUE
J 0
(-5450 2425);
DISPLAY 0.872340 (-5450 2425);
DISPLAY INVISIBLE (-5450 2425);
FORCEPROP 1 LAST PATH I52
J 0
(-5777 2550);
DISPLAY 0.872340 (-5777 2550);
PAINT GREEN (-5777 2550);
DISPLAY INVISIBLE (-5777 2550);
FORCEADD TAP..1
(-5775 2600);
FORCEPROP 3 LASTPIN (-5825 2600) SIG_NAME M_G_CPU1_SB_DQ<9>
J 0
(-5815 2610);
DISPLAY 0.659574 (-5815 2610);
PAINT MONO (-5815 2610);
DISPLAY INVISIBLE (-5815 2610);
FORCEPROP 1 LASTPIN (-5825 2600) BN 9
J 0
(-5837 2608);
DISPLAY 0.489362 (-5837 2608);
PAINT GREEN (-5837 2608);
FORCEPROP 2 LAST CDS_LIB mstr_standard
J 0
(-5775 2600);
DISPLAY 0.723404 (-5775 2600);
PAINT MONO (-5775 2600);
DISPLAY INVISIBLE (-5775 2600);
FORCEPROP 1 LAST BODY_TYPE PLUMBING
J 0
(-5775 2650);
DISPLAY 0.872340 (-5775 2650);
PAINT GREEN (-5775 2650);
DISPLAY INVISIBLE (-5775 2650);
FORCEPROP 1 LAST HDL_TAP TRUE
J 0
(-5450 2475);
DISPLAY 0.872340 (-5450 2475);
DISPLAY INVISIBLE (-5450 2475);
FORCEPROP 1 LAST PATH I53
J 0
(-5777 2600);
DISPLAY 0.872340 (-5777 2600);
PAINT GREEN (-5777 2600);
DISPLAY INVISIBLE (-5777 2600);
FORCEADD TAP..1
(-5775 2950);
FORCEPROP 3 LASTPIN (-5825 2950) SIG_NAME M_G_CPU1_SB_DQ<16>
J 0
(-5815 2960);
DISPLAY 0.659574 (-5815 2960);
PAINT MONO (-5815 2960);
DISPLAY INVISIBLE (-5815 2960);
FORCEPROP 1 LASTPIN (-5825 2950) BN 16
J 0
(-5837 2958);
DISPLAY 0.489362 (-5837 2958);
PAINT GREEN (-5837 2958);
FORCEPROP 2 LAST CDS_LIB mstr_standard
J 0
(-5775 2950);
DISPLAY 0.723404 (-5775 2950);
PAINT MONO (-5775 2950);
DISPLAY INVISIBLE (-5775 2950);
FORCEPROP 1 LAST BODY_TYPE PLUMBING
J 0
(-5775 3000);
DISPLAY 0.872340 (-5775 3000);
PAINT GREEN (-5775 3000);
DISPLAY INVISIBLE (-5775 3000);
FORCEPROP 1 LAST HDL_TAP TRUE
J 0
(-5450 2825);
DISPLAY 0.872340 (-5450 2825);
DISPLAY INVISIBLE (-5450 2825);
FORCEPROP 1 LAST PATH I54
J 0
(-5777 2950);
DISPLAY 0.872340 (-5777 2950);
PAINT GREEN (-5777 2950);
DISPLAY INVISIBLE (-5777 2950);
FORCEADD TAP..1
(-5775 2900);
FORCEPROP 3 LASTPIN (-5825 2900) SIG_NAME M_G_CPU1_SB_DQ<15>
J 0
(-5815 2910);
DISPLAY 0.659574 (-5815 2910);
PAINT MONO (-5815 2910);
DISPLAY INVISIBLE (-5815 2910);
FORCEPROP 1 LASTPIN (-5825 2900) BN 15
J 0
(-5837 2908);
DISPLAY 0.489362 (-5837 2908);
PAINT GREEN (-5837 2908);
FORCEPROP 2 LAST CDS_LIB mstr_standard
J 0
(-5775 2900);
DISPLAY 0.723404 (-5775 2900);
PAINT MONO (-5775 2900);
DISPLAY INVISIBLE (-5775 2900);
FORCEPROP 1 LAST BODY_TYPE PLUMBING
J 0
(-5775 2950);
DISPLAY 0.872340 (-5775 2950);
PAINT GREEN (-5775 2950);
DISPLAY INVISIBLE (-5775 2950);
FORCEPROP 1 LAST HDL_TAP TRUE
J 0
(-5450 2775);
DISPLAY 0.872340 (-5450 2775);
DISPLAY INVISIBLE (-5450 2775);
FORCEPROP 1 LAST PATH I55
J 0
(-5777 2900);
DISPLAY 0.872340 (-5777 2900);
PAINT GREEN (-5777 2900);
DISPLAY INVISIBLE (-5777 2900);
FORCEADD TAP..1
(-5775 3000);
FORCEPROP 3 LASTPIN (-5825 3000) SIG_NAME M_G_CPU1_SB_DQ<17>
J 0
(-5815 3010);
DISPLAY 0.659574 (-5815 3010);
PAINT MONO (-5815 3010);
DISPLAY INVISIBLE (-5815 3010);
FORCEPROP 1 LASTPIN (-5825 3000) BN 17
J 0
(-5837 3008);
DISPLAY 0.489362 (-5837 3008);
PAINT GREEN (-5837 3008);
FORCEPROP 2 LAST CDS_LIB mstr_standard
J 0
(-5775 3000);
DISPLAY 0.723404 (-5775 3000);
PAINT MONO (-5775 3000);
DISPLAY INVISIBLE (-5775 3000);
FORCEPROP 1 LAST BODY_TYPE PLUMBING
J 0
(-5775 3050);
DISPLAY 0.872340 (-5775 3050);
PAINT GREEN (-5775 3050);
DISPLAY INVISIBLE (-5775 3050);
FORCEPROP 1 LAST HDL_TAP TRUE
J 0
(-5450 2875);
DISPLAY 0.872340 (-5450 2875);
DISPLAY INVISIBLE (-5450 2875);
FORCEPROP 1 LAST PATH I56
J 0
(-5777 3000);
DISPLAY 0.872340 (-5777 3000);
PAINT GREEN (-5777 3000);
DISPLAY INVISIBLE (-5777 3000);
FORCEADD TAP..1
(-5775 2750);
FORCEPROP 3 LASTPIN (-5825 2750) SIG_NAME M_G_CPU1_SB_DQ<12>
J 0
(-5815 2760);
DISPLAY 0.659574 (-5815 2760);
PAINT MONO (-5815 2760);
DISPLAY INVISIBLE (-5815 2760);
FORCEPROP 1 LASTPIN (-5825 2750) BN 12
J 0
(-5837 2758);
DISPLAY 0.489362 (-5837 2758);
PAINT GREEN (-5837 2758);
FORCEPROP 2 LAST CDS_LIB mstr_standard
J 0
(-5775 2750);
DISPLAY 0.723404 (-5775 2750);
PAINT MONO (-5775 2750);
DISPLAY INVISIBLE (-5775 2750);
FORCEPROP 1 LAST BODY_TYPE PLUMBING
J 0
(-5775 2800);
DISPLAY 0.872340 (-5775 2800);
PAINT GREEN (-5775 2800);
DISPLAY INVISIBLE (-5775 2800);
FORCEPROP 1 LAST HDL_TAP TRUE
J 0
(-5450 2625);
DISPLAY 0.872340 (-5450 2625);
DISPLAY INVISIBLE (-5450 2625);
FORCEPROP 1 LAST PATH I57
J 0
(-5777 2750);
DISPLAY 0.872340 (-5777 2750);
PAINT GREEN (-5777 2750);
DISPLAY INVISIBLE (-5777 2750);
FORCEADD TAP..1
(-5775 2800);
FORCEPROP 3 LASTPIN (-5825 2800) SIG_NAME M_G_CPU1_SB_DQ<13>
J 0
(-5815 2810);
DISPLAY 0.659574 (-5815 2810);
PAINT MONO (-5815 2810);
DISPLAY INVISIBLE (-5815 2810);
FORCEPROP 1 LASTPIN (-5825 2800) BN 13
J 0
(-5837 2808);
DISPLAY 0.489362 (-5837 2808);
PAINT GREEN (-5837 2808);
FORCEPROP 2 LAST CDS_LIB mstr_standard
J 0
(-5775 2800);
DISPLAY 0.723404 (-5775 2800);
PAINT MONO (-5775 2800);
DISPLAY INVISIBLE (-5775 2800);
FORCEPROP 1 LAST BODY_TYPE PLUMBING
J 0
(-5775 2850);
DISPLAY 0.872340 (-5775 2850);
PAINT GREEN (-5775 2850);
DISPLAY INVISIBLE (-5775 2850);
FORCEPROP 1 LAST HDL_TAP TRUE
J 0
(-5450 2675);
DISPLAY 0.872340 (-5450 2675);
DISPLAY INVISIBLE (-5450 2675);
FORCEPROP 1 LAST PATH I58
J 0
(-5777 2800);
DISPLAY 0.872340 (-5777 2800);
PAINT GREEN (-5777 2800);
DISPLAY INVISIBLE (-5777 2800);
FORCEADD TAP..1
(-5775 2850);
FORCEPROP 3 LASTPIN (-5825 2850) SIG_NAME M_G_CPU1_SB_DQ<14>
J 0
(-5815 2860);
DISPLAY 0.659574 (-5815 2860);
PAINT MONO (-5815 2860);
DISPLAY INVISIBLE (-5815 2860);
FORCEPROP 1 LASTPIN (-5825 2850) BN 14
J 0
(-5837 2858);
DISPLAY 0.489362 (-5837 2858);
PAINT GREEN (-5837 2858);
FORCEPROP 2 LAST CDS_LIB mstr_standard
J 0
(-5775 2850);
DISPLAY 0.723404 (-5775 2850);
PAINT MONO (-5775 2850);
DISPLAY INVISIBLE (-5775 2850);
FORCEPROP 1 LAST BODY_TYPE PLUMBING
J 0
(-5775 2900);
DISPLAY 0.872340 (-5775 2900);
PAINT GREEN (-5775 2900);
DISPLAY INVISIBLE (-5775 2900);
FORCEPROP 1 LAST HDL_TAP TRUE
J 0
(-5450 2725);
DISPLAY 0.872340 (-5450 2725);
DISPLAY INVISIBLE (-5450 2725);
FORCEPROP 1 LAST PATH I59
J 0
(-5777 2850);
DISPLAY 0.872340 (-5777 2850);
PAINT GREEN (-5777 2850);
DISPLAY INVISIBLE (-5777 2850);
FORCEADD TAP..1
(-5775 3150);
FORCEPROP 3 LASTPIN (-5825 3150) SIG_NAME M_G_CPU1_SB_DQ<20>
J 0
(-5815 3160);
DISPLAY 0.659574 (-5815 3160);
PAINT MONO (-5815 3160);
DISPLAY INVISIBLE (-5815 3160);
FORCEPROP 1 LASTPIN (-5825 3150) BN 20
J 0
(-5837 3158);
DISPLAY 0.489362 (-5837 3158);
PAINT GREEN (-5837 3158);
FORCEPROP 2 LAST CDS_LIB mstr_standard
J 0
(-5775 3150);
DISPLAY 0.723404 (-5775 3150);
PAINT MONO (-5775 3150);
DISPLAY INVISIBLE (-5775 3150);
FORCEPROP 1 LAST BODY_TYPE PLUMBING
J 0
(-5775 3200);
DISPLAY 0.872340 (-5775 3200);
PAINT GREEN (-5775 3200);
DISPLAY INVISIBLE (-5775 3200);
FORCEPROP 1 LAST HDL_TAP TRUE
J 0
(-5450 3025);
DISPLAY 0.872340 (-5450 3025);
DISPLAY INVISIBLE (-5450 3025);
FORCEPROP 1 LAST PATH I60
J 0
(-5777 3150);
DISPLAY 0.872340 (-5777 3150);
PAINT GREEN (-5777 3150);
DISPLAY INVISIBLE (-5777 3150);
FORCEADD TAP..1
(-5775 3200);
FORCEPROP 3 LASTPIN (-5825 3200) SIG_NAME M_G_CPU1_SB_DQ<21>
J 0
(-5815 3210);
DISPLAY 0.659574 (-5815 3210);
PAINT MONO (-5815 3210);
DISPLAY INVISIBLE (-5815 3210);
FORCEPROP 1 LASTPIN (-5825 3200) BN 21
J 0
(-5837 3208);
DISPLAY 0.489362 (-5837 3208);
PAINT GREEN (-5837 3208);
FORCEPROP 2 LAST CDS_LIB mstr_standard
J 0
(-5775 3200);
DISPLAY 0.723404 (-5775 3200);
PAINT MONO (-5775 3200);
DISPLAY INVISIBLE (-5775 3200);
FORCEPROP 1 LAST BODY_TYPE PLUMBING
J 0
(-5775 3250);
DISPLAY 0.872340 (-5775 3250);
PAINT GREEN (-5775 3250);
DISPLAY INVISIBLE (-5775 3250);
FORCEPROP 1 LAST HDL_TAP TRUE
J 0
(-5450 3075);
DISPLAY 0.872340 (-5450 3075);
DISPLAY INVISIBLE (-5450 3075);
FORCEPROP 1 LAST PATH I61
J 0
(-5777 3200);
DISPLAY 0.872340 (-5777 3200);
PAINT GREEN (-5777 3200);
DISPLAY INVISIBLE (-5777 3200);
FORCEADD TAP..1
(-5775 3250);
FORCEPROP 3 LASTPIN (-5825 3250) SIG_NAME M_G_CPU1_SB_DQ<22>
J 0
(-5815 3260);
DISPLAY 0.659574 (-5815 3260);
PAINT MONO (-5815 3260);
DISPLAY INVISIBLE (-5815 3260);
FORCEPROP 1 LASTPIN (-5825 3250) BN 22
J 0
(-5837 3258);
DISPLAY 0.489362 (-5837 3258);
PAINT GREEN (-5837 3258);
FORCEPROP 2 LAST CDS_LIB mstr_standard
J 0
(-5775 3250);
DISPLAY 0.723404 (-5775 3250);
PAINT MONO (-5775 3250);
DISPLAY INVISIBLE (-5775 3250);
FORCEPROP 1 LAST BODY_TYPE PLUMBING
J 0
(-5775 3300);
DISPLAY 0.872340 (-5775 3300);
PAINT GREEN (-5775 3300);
DISPLAY INVISIBLE (-5775 3300);
FORCEPROP 1 LAST HDL_TAP TRUE
J 0
(-5450 3125);
DISPLAY 0.872340 (-5450 3125);
DISPLAY INVISIBLE (-5450 3125);
FORCEPROP 1 LAST PATH I62
J 0
(-5777 3250);
DISPLAY 0.872340 (-5777 3250);
PAINT GREEN (-5777 3250);
DISPLAY INVISIBLE (-5777 3250);
FORCEADD TAP..1
(-5775 3050);
FORCEPROP 3 LASTPIN (-5825 3050) SIG_NAME M_G_CPU1_SB_DQ<18>
J 0
(-5815 3060);
DISPLAY 0.659574 (-5815 3060);
PAINT MONO (-5815 3060);
DISPLAY INVISIBLE (-5815 3060);
FORCEPROP 1 LASTPIN (-5825 3050) BN 18
J 0
(-5837 3058);
DISPLAY 0.489362 (-5837 3058);
PAINT GREEN (-5837 3058);
FORCEPROP 2 LAST CDS_LIB mstr_standard
J 0
(-5775 3050);
DISPLAY 0.723404 (-5775 3050);
PAINT MONO (-5775 3050);
DISPLAY INVISIBLE (-5775 3050);
FORCEPROP 1 LAST BODY_TYPE PLUMBING
J 0
(-5775 3100);
DISPLAY 0.872340 (-5775 3100);
PAINT GREEN (-5775 3100);
DISPLAY INVISIBLE (-5775 3100);
FORCEPROP 1 LAST HDL_TAP TRUE
J 0
(-5450 2925);
DISPLAY 0.872340 (-5450 2925);
DISPLAY INVISIBLE (-5450 2925);
FORCEPROP 1 LAST PATH I63
J 0
(-5777 3050);
DISPLAY 0.872340 (-5777 3050);
PAINT GREEN (-5777 3050);
DISPLAY INVISIBLE (-5777 3050);
FORCEADD TAP..1
(-5775 3100);
FORCEPROP 3 LASTPIN (-5825 3100) SIG_NAME M_G_CPU1_SB_DQ<19>
J 0
(-5815 3110);
DISPLAY 0.659574 (-5815 3110);
PAINT MONO (-5815 3110);
DISPLAY INVISIBLE (-5815 3110);
FORCEPROP 1 LASTPIN (-5825 3100) BN 19
J 0
(-5837 3108);
DISPLAY 0.489362 (-5837 3108);
PAINT GREEN (-5837 3108);
FORCEPROP 2 LAST CDS_LIB mstr_standard
J 0
(-5775 3100);
DISPLAY 0.723404 (-5775 3100);
PAINT MONO (-5775 3100);
DISPLAY INVISIBLE (-5775 3100);
FORCEPROP 1 LAST BODY_TYPE PLUMBING
J 0
(-5775 3150);
DISPLAY 0.872340 (-5775 3150);
PAINT GREEN (-5775 3150);
DISPLAY INVISIBLE (-5775 3150);
FORCEPROP 1 LAST HDL_TAP TRUE
J 0
(-5450 2975);
DISPLAY 0.872340 (-5450 2975);
DISPLAY INVISIBLE (-5450 2975);
FORCEPROP 1 LAST PATH I64
J 0
(-5777 3100);
DISPLAY 0.872340 (-5777 3100);
PAINT GREEN (-5777 3100);
DISPLAY INVISIBLE (-5777 3100);
FORCEADD TAP..1
(-5775 3400);
FORCEPROP 3 LASTPIN (-5825 3400) SIG_NAME M_G_CPU1_SB_DQ<25>
J 0
(-5815 3410);
DISPLAY 0.659574 (-5815 3410);
PAINT MONO (-5815 3410);
DISPLAY INVISIBLE (-5815 3410);
FORCEPROP 1 LASTPIN (-5825 3400) BN 25
J 0
(-5837 3408);
DISPLAY 0.489362 (-5837 3408);
PAINT GREEN (-5837 3408);
FORCEPROP 2 LAST CDS_LIB mstr_standard
J 0
(-5775 3400);
DISPLAY 0.723404 (-5775 3400);
PAINT MONO (-5775 3400);
DISPLAY INVISIBLE (-5775 3400);
FORCEPROP 1 LAST BODY_TYPE PLUMBING
J 0
(-5775 3450);
DISPLAY 0.872340 (-5775 3450);
PAINT GREEN (-5775 3450);
DISPLAY INVISIBLE (-5775 3450);
FORCEPROP 1 LAST HDL_TAP TRUE
J 0
(-5450 3275);
DISPLAY 0.872340 (-5450 3275);
DISPLAY INVISIBLE (-5450 3275);
FORCEPROP 1 LAST PATH I65
J 0
(-5777 3400);
DISPLAY 0.872340 (-5777 3400);
PAINT GREEN (-5777 3400);
DISPLAY INVISIBLE (-5777 3400);
FORCEADD TAP..1
(-5775 3450);
FORCEPROP 3 LASTPIN (-5825 3450) SIG_NAME M_G_CPU1_SB_DQ<26>
J 0
(-5815 3460);
DISPLAY 0.659574 (-5815 3460);
PAINT MONO (-5815 3460);
DISPLAY INVISIBLE (-5815 3460);
FORCEPROP 1 LASTPIN (-5825 3450) BN 26
J 0
(-5837 3458);
DISPLAY 0.489362 (-5837 3458);
PAINT GREEN (-5837 3458);
FORCEPROP 2 LAST CDS_LIB mstr_standard
J 0
(-5775 3450);
DISPLAY 0.723404 (-5775 3450);
PAINT MONO (-5775 3450);
DISPLAY INVISIBLE (-5775 3450);
FORCEPROP 1 LAST BODY_TYPE PLUMBING
J 0
(-5775 3500);
DISPLAY 0.872340 (-5775 3500);
PAINT GREEN (-5775 3500);
DISPLAY INVISIBLE (-5775 3500);
FORCEPROP 1 LAST HDL_TAP TRUE
J 0
(-5450 3325);
DISPLAY 0.872340 (-5450 3325);
DISPLAY INVISIBLE (-5450 3325);
FORCEPROP 1 LAST PATH I66
J 0
(-5777 3450);
DISPLAY 0.872340 (-5777 3450);
PAINT GREEN (-5777 3450);
DISPLAY INVISIBLE (-5777 3450);
FORCEADD TAP..1
(-5775 3500);
FORCEPROP 3 LASTPIN (-5825 3500) SIG_NAME M_G_CPU1_SB_DQ<27>
J 0
(-5815 3510);
DISPLAY 0.659574 (-5815 3510);
PAINT MONO (-5815 3510);
DISPLAY INVISIBLE (-5815 3510);
FORCEPROP 1 LASTPIN (-5825 3500) BN 27
J 0
(-5837 3508);
DISPLAY 0.489362 (-5837 3508);
PAINT GREEN (-5837 3508);
FORCEPROP 2 LAST CDS_LIB mstr_standard
J 0
(-5775 3500);
DISPLAY 0.723404 (-5775 3500);
PAINT MONO (-5775 3500);
DISPLAY INVISIBLE (-5775 3500);
FORCEPROP 1 LAST BODY_TYPE PLUMBING
J 0
(-5775 3550);
DISPLAY 0.872340 (-5775 3550);
PAINT GREEN (-5775 3550);
DISPLAY INVISIBLE (-5775 3550);
FORCEPROP 1 LAST HDL_TAP TRUE
J 0
(-5450 3375);
DISPLAY 0.872340 (-5450 3375);
DISPLAY INVISIBLE (-5450 3375);
FORCEPROP 1 LAST PATH I67
J 0
(-5777 3500);
DISPLAY 0.872340 (-5777 3500);
PAINT GREEN (-5777 3500);
DISPLAY INVISIBLE (-5777 3500);
FORCEADD TAP..1
(-5775 3300);
FORCEPROP 3 LASTPIN (-5825 3300) SIG_NAME M_G_CPU1_SB_DQ<23>
J 0
(-5815 3310);
DISPLAY 0.659574 (-5815 3310);
PAINT MONO (-5815 3310);
DISPLAY INVISIBLE (-5815 3310);
FORCEPROP 1 LASTPIN (-5825 3300) BN 23
J 0
(-5837 3308);
DISPLAY 0.489362 (-5837 3308);
PAINT GREEN (-5837 3308);
FORCEPROP 2 LAST CDS_LIB mstr_standard
J 0
(-5775 3300);
DISPLAY 0.723404 (-5775 3300);
PAINT MONO (-5775 3300);
DISPLAY INVISIBLE (-5775 3300);
FORCEPROP 1 LAST BODY_TYPE PLUMBING
J 0
(-5775 3350);
DISPLAY 0.872340 (-5775 3350);
PAINT GREEN (-5775 3350);
DISPLAY INVISIBLE (-5775 3350);
FORCEPROP 1 LAST HDL_TAP TRUE
J 0
(-5450 3175);
DISPLAY 0.872340 (-5450 3175);
DISPLAY INVISIBLE (-5450 3175);
FORCEPROP 1 LAST PATH I68
J 0
(-5777 3300);
DISPLAY 0.872340 (-5777 3300);
PAINT GREEN (-5777 3300);
DISPLAY INVISIBLE (-5777 3300);
FORCEADD TAP..1
(-5775 3350);
FORCEPROP 3 LASTPIN (-5825 3350) SIG_NAME M_G_CPU1_SB_DQ<24>
J 0
(-5815 3360);
DISPLAY 0.659574 (-5815 3360);
PAINT MONO (-5815 3360);
DISPLAY INVISIBLE (-5815 3360);
FORCEPROP 1 LASTPIN (-5825 3350) BN 24
J 0
(-5837 3358);
DISPLAY 0.489362 (-5837 3358);
PAINT GREEN (-5837 3358);
FORCEPROP 2 LAST CDS_LIB mstr_standard
J 0
(-5775 3350);
DISPLAY 0.723404 (-5775 3350);
PAINT MONO (-5775 3350);
DISPLAY INVISIBLE (-5775 3350);
FORCEPROP 1 LAST BODY_TYPE PLUMBING
J 0
(-5775 3400);
DISPLAY 0.872340 (-5775 3400);
PAINT GREEN (-5775 3400);
DISPLAY INVISIBLE (-5775 3400);
FORCEPROP 1 LAST HDL_TAP TRUE
J 0
(-5450 3225);
DISPLAY 0.872340 (-5450 3225);
DISPLAY INVISIBLE (-5450 3225);
FORCEPROP 1 LAST PATH I69
J 0
(-5777 3350);
DISPLAY 0.872340 (-5777 3350);
PAINT GREEN (-5777 3350);
DISPLAY INVISIBLE (-5777 3350);
FORCEADD OFFPAGE..5
(-8075 3000);
FORCEPROP 2 LAST $XR0 43 
J 0
(-8329 3000);
DISPLAY 0.638298 (-8329 3000);
PAINT MONO (-8329 3000);
FORCEPROP 2 LAST CDS_LIB mstr_standard
J 0
(-8075 3000);
DISPLAY INVISIBLE (-8075 3000);
FORCEPROP 1 LAST OFFPAGE TRUE
J 0
(-7750 2875);
DISPLAY 0.872340 (-7750 2875);
PAINT GREEN (-7750 2875);
DISPLAY INVISIBLE (-7750 2875);
FORCEPROP 1 LAST COMMENT_BODY TRUE
J 0
(-7975 2925);
DISPLAY 0.872340 (-7975 2925);
PAINT GREEN (-7975 2925);
DISPLAY INVISIBLE (-7975 2925);
FORCEPROP 2 LAST PATH I7
J 0
(-8325 3050);
DISPLAY 1.021277 (-8325 3050);
DISPLAY INVISIBLE (-8325 3050);
FORCEADD TAP..1
(-5775 3650);
FORCEPROP 3 LASTPIN (-5825 3650) SIG_NAME M_G_CPU1_SB_DQ<30>
J 0
(-5815 3660);
DISPLAY 0.659574 (-5815 3660);
PAINT MONO (-5815 3660);
DISPLAY INVISIBLE (-5815 3660);
FORCEPROP 1 LASTPIN (-5825 3650) BN 30
J 0
(-5837 3658);
DISPLAY 0.489362 (-5837 3658);
PAINT GREEN (-5837 3658);
FORCEPROP 2 LAST CDS_LIB mstr_standard
J 0
(-5775 3650);
DISPLAY 0.723404 (-5775 3650);
PAINT MONO (-5775 3650);
DISPLAY INVISIBLE (-5775 3650);
FORCEPROP 1 LAST BODY_TYPE PLUMBING
J 0
(-5775 3700);
DISPLAY 0.872340 (-5775 3700);
PAINT GREEN (-5775 3700);
DISPLAY INVISIBLE (-5775 3700);
FORCEPROP 1 LAST HDL_TAP TRUE
J 0
(-5450 3525);
DISPLAY 0.872340 (-5450 3525);
DISPLAY INVISIBLE (-5450 3525);
FORCEPROP 1 LAST PATH I70
J 0
(-5777 3650);
DISPLAY 0.872340 (-5777 3650);
PAINT GREEN (-5777 3650);
DISPLAY INVISIBLE (-5777 3650);
FORCEADD TAP..1
(-5775 3700);
FORCEPROP 3 LASTPIN (-5825 3700) SIG_NAME M_G_CPU1_SB_DQ<31>
J 0
(-5815 3710);
DISPLAY 0.659574 (-5815 3710);
PAINT MONO (-5815 3710);
DISPLAY INVISIBLE (-5815 3710);
FORCEPROP 1 LASTPIN (-5825 3700) BN 31
J 0
(-5837 3708);
DISPLAY 0.489362 (-5837 3708);
PAINT GREEN (-5837 3708);
FORCEPROP 2 LAST CDS_LIB mstr_standard
J 0
(-5775 3700);
DISPLAY 0.723404 (-5775 3700);
PAINT MONO (-5775 3700);
DISPLAY INVISIBLE (-5775 3700);
FORCEPROP 1 LAST BODY_TYPE PLUMBING
J 0
(-5775 3750);
DISPLAY 0.872340 (-5775 3750);
PAINT GREEN (-5775 3750);
DISPLAY INVISIBLE (-5775 3750);
FORCEPROP 1 LAST HDL_TAP TRUE
J 0
(-5450 3575);
DISPLAY 0.872340 (-5450 3575);
DISPLAY INVISIBLE (-5450 3575);
FORCEPROP 1 LAST PATH I71
J 0
(-5777 3700);
DISPLAY 0.872340 (-5777 3700);
PAINT GREEN (-5777 3700);
DISPLAY INVISIBLE (-5777 3700);
FORCEADD TAP..1
(-5775 3550);
FORCEPROP 3 LASTPIN (-5825 3550) SIG_NAME M_G_CPU1_SB_DQ<28>
J 0
(-5815 3560);
DISPLAY 0.659574 (-5815 3560);
PAINT MONO (-5815 3560);
DISPLAY INVISIBLE (-5815 3560);
FORCEPROP 1 LASTPIN (-5825 3550) BN 28
J 0
(-5837 3558);
DISPLAY 0.489362 (-5837 3558);
PAINT GREEN (-5837 3558);
FORCEPROP 2 LAST CDS_LIB mstr_standard
J 0
(-5775 3550);
DISPLAY 0.723404 (-5775 3550);
PAINT MONO (-5775 3550);
DISPLAY INVISIBLE (-5775 3550);
FORCEPROP 1 LAST BODY_TYPE PLUMBING
J 0
(-5775 3600);
DISPLAY 0.872340 (-5775 3600);
PAINT GREEN (-5775 3600);
DISPLAY INVISIBLE (-5775 3600);
FORCEPROP 1 LAST HDL_TAP TRUE
J 0
(-5450 3425);
DISPLAY 0.872340 (-5450 3425);
DISPLAY INVISIBLE (-5450 3425);
FORCEPROP 1 LAST PATH I72
J 0
(-5777 3550);
DISPLAY 0.872340 (-5777 3550);
PAINT GREEN (-5777 3550);
DISPLAY INVISIBLE (-5777 3550);
FORCEADD TAP..1
(-5775 3600);
FORCEPROP 3 LASTPIN (-5825 3600) SIG_NAME M_G_CPU1_SB_DQ<29>
J 0
(-5815 3610);
DISPLAY 0.659574 (-5815 3610);
PAINT MONO (-5815 3610);
DISPLAY INVISIBLE (-5815 3610);
FORCEPROP 1 LASTPIN (-5825 3600) BN 29
J 0
(-5837 3608);
DISPLAY 0.489362 (-5837 3608);
PAINT GREEN (-5837 3608);
FORCEPROP 2 LAST CDS_LIB mstr_standard
J 0
(-5775 3600);
DISPLAY 0.723404 (-5775 3600);
PAINT MONO (-5775 3600);
DISPLAY INVISIBLE (-5775 3600);
FORCEPROP 1 LAST BODY_TYPE PLUMBING
J 0
(-5775 3650);
DISPLAY 0.872340 (-5775 3650);
PAINT GREEN (-5775 3650);
DISPLAY INVISIBLE (-5775 3650);
FORCEPROP 1 LAST HDL_TAP TRUE
J 0
(-5450 3475);
DISPLAY 0.872340 (-5450 3475);
DISPLAY INVISIBLE (-5450 3475);
FORCEPROP 1 LAST PATH I73
J 0
(-5777 3600);
DISPLAY 0.872340 (-5777 3600);
PAINT GREEN (-5777 3600);
DISPLAY INVISIBLE (-5777 3600);
FORCEADD OFFPAGE..3
(-5175 3750);
FORCEPROP 2 LAST $XR0 43 
J 0
(-4961 3750);
DISPLAY 0.638298 (-4961 3750);
PAINT MONO (-4961 3750);
FORCEPROP 2 LAST CDS_LIB mstr_standard
J 0
(-5175 3750);
DISPLAY 0.723404 (-5175 3750);
PAINT MONO (-5175 3750);
DISPLAY INVISIBLE (-5175 3750);
FORCEPROP 1 LAST OFFPAGE TRUE
J 0
(-4850 3625);
DISPLAY 0.872340 (-4850 3625);
PAINT GREEN (-4850 3625);
DISPLAY INVISIBLE (-4850 3625);
FORCEPROP 1 LAST COMMENT_BODY TRUE
J 0
(-5225 3650);
DISPLAY 0.872340 (-5225 3650);
PAINT GREEN (-5225 3650);
DISPLAY INVISIBLE (-5225 3650);
FORCEPROP 2 LAST PATH I74
J 0
(-4850 3800);
DISPLAY 1.021277 (-4850 3800);
DISPLAY INVISIBLE (-4850 3800);
FORCEADD TAP..1
R 2
(-7475 3800);
FORCEPROP 3 LASTPIN (-7425 3800) SIG_NAME M_G_CPU1_SA_CB<4>
J 0
(-7415 3810);
DISPLAY 0.659574 (-7415 3810);
PAINT MONO (-7415 3810);
DISPLAY INVISIBLE (-7415 3810);
FORCEPROP 1 LASTPIN (-7425 3800) BN 4
J 2
(-7413 3808);
DISPLAY 0.489362 (-7413 3808);
PAINT GREEN (-7413 3808);
FORCEPROP 2 LAST CDS_LIB mstr_standard
J 0
(-7475 3800);
DISPLAY 0.723404 (-7475 3800);
PAINT MONO (-7475 3800);
DISPLAY INVISIBLE (-7475 3800);
FORCEPROP 1 LAST BODY_TYPE PLUMBING
J 2
(-7475 3850);
DISPLAY 0.872340 (-7475 3850);
PAINT GREEN (-7475 3850);
DISPLAY INVISIBLE (-7475 3850);
FORCEPROP 1 LAST HDL_TAP TRUE
J 2
(-7800 3675);
DISPLAY 0.872340 (-7800 3675);
DISPLAY INVISIBLE (-7800 3675);
FORCEPROP 1 LAST PATH I76
J 2
(-7473 3800);
DISPLAY 0.872340 (-7473 3800);
PAINT GREEN (-7473 3800);
DISPLAY INVISIBLE (-7473 3800);
FORCEADD TAP..1
R 2
(-7475 3850);
FORCEPROP 3 LASTPIN (-7425 3850) SIG_NAME M_G_CPU1_SA_CB<5>
J 0
(-7415 3860);
DISPLAY 0.659574 (-7415 3860);
PAINT MONO (-7415 3860);
DISPLAY INVISIBLE (-7415 3860);
FORCEPROP 1 LASTPIN (-7425 3850) BN 5
J 2
(-7413 3858);
DISPLAY 0.489362 (-7413 3858);
PAINT GREEN (-7413 3858);
FORCEPROP 2 LAST CDS_LIB mstr_standard
J 0
(-7475 3850);
DISPLAY 0.723404 (-7475 3850);
PAINT MONO (-7475 3850);
DISPLAY INVISIBLE (-7475 3850);
FORCEPROP 1 LAST BODY_TYPE PLUMBING
J 2
(-7475 3900);
DISPLAY 0.872340 (-7475 3900);
PAINT GREEN (-7475 3900);
DISPLAY INVISIBLE (-7475 3900);
FORCEPROP 1 LAST HDL_TAP TRUE
J 2
(-7800 3725);
DISPLAY 0.872340 (-7800 3725);
DISPLAY INVISIBLE (-7800 3725);
FORCEPROP 1 LAST PATH I77
J 2
(-7473 3850);
DISPLAY 0.872340 (-7473 3850);
PAINT GREEN (-7473 3850);
DISPLAY INVISIBLE (-7473 3850);
FORCEADD TAP..1
R 2
(-7475 3900);
FORCEPROP 3 LASTPIN (-7425 3900) SIG_NAME M_G_CPU1_SA_CB<6>
J 0
(-7415 3910);
DISPLAY 0.659574 (-7415 3910);
PAINT MONO (-7415 3910);
DISPLAY INVISIBLE (-7415 3910);
FORCEPROP 1 LASTPIN (-7425 3900) BN 6
J 2
(-7413 3908);
DISPLAY 0.489362 (-7413 3908);
PAINT GREEN (-7413 3908);
FORCEPROP 2 LAST CDS_LIB mstr_standard
J 0
(-7475 3900);
DISPLAY 0.723404 (-7475 3900);
PAINT MONO (-7475 3900);
DISPLAY INVISIBLE (-7475 3900);
FORCEPROP 1 LAST BODY_TYPE PLUMBING
J 2
(-7475 3950);
DISPLAY 0.872340 (-7475 3950);
PAINT GREEN (-7475 3950);
DISPLAY INVISIBLE (-7475 3950);
FORCEPROP 1 LAST HDL_TAP TRUE
J 2
(-7800 3775);
DISPLAY 0.872340 (-7800 3775);
DISPLAY INVISIBLE (-7800 3775);
FORCEPROP 1 LAST PATH I78
J 2
(-7473 3900);
DISPLAY 0.872340 (-7473 3900);
PAINT GREEN (-7473 3900);
DISPLAY INVISIBLE (-7473 3900);
FORCEADD TAP..1
R 2
(-7475 3950);
FORCEPROP 3 LASTPIN (-7425 3950) SIG_NAME M_G_CPU1_SA_CB<7>
J 0
(-7415 3960);
DISPLAY 0.659574 (-7415 3960);
PAINT MONO (-7415 3960);
DISPLAY INVISIBLE (-7415 3960);
FORCEPROP 1 LASTPIN (-7425 3950) BN 7
J 2
(-7413 3958);
DISPLAY 0.489362 (-7413 3958);
PAINT GREEN (-7413 3958);
FORCEPROP 2 LAST CDS_LIB mstr_standard
J 0
(-7475 3950);
DISPLAY 0.723404 (-7475 3950);
PAINT MONO (-7475 3950);
DISPLAY INVISIBLE (-7475 3950);
FORCEPROP 1 LAST BODY_TYPE PLUMBING
J 2
(-7475 4000);
DISPLAY 0.872340 (-7475 4000);
PAINT GREEN (-7475 4000);
DISPLAY INVISIBLE (-7475 4000);
FORCEPROP 1 LAST HDL_TAP TRUE
J 2
(-7800 3825);
DISPLAY 0.872340 (-7800 3825);
DISPLAY INVISIBLE (-7800 3825);
FORCEPROP 1 LAST PATH I79
J 2
(-7473 3950);
DISPLAY 0.872340 (-7473 3950);
PAINT GREEN (-7473 3950);
DISPLAY INVISIBLE (-7473 3950);
FORCEADD OFFPAGE..1
(-8375 2850);
FORCEPROP 2 LAST $XR0 104 
J 0
(-8657 2850);
DISPLAY 0.638298 (-8657 2850);
PAINT MONO (-8657 2850);
FORCEPROP 2 LAST CDS_LIB mstr_standard
J 0
(-8375 2850);
DISPLAY 0.808511 (-8375 2850);
DISPLAY INVISIBLE (-8375 2850);
FORCEPROP 1 LAST OFFPAGE TRUE
J 0
(-8050 2725);
DISPLAY 0.872340 (-8050 2725);
PAINT GREEN (-8050 2725);
DISPLAY INVISIBLE (-8050 2725);
FORCEPROP 1 LAST COMMENT_BODY TRUE
J 0
(-8250 2750);
DISPLAY 0.872340 (-8250 2750);
PAINT GREEN (-8250 2750);
DISPLAY INVISIBLE (-8250 2750);
FORCEPROP 2 LAST PATH I8
J 0
(-8650 2900);
DISPLAY 1.021277 (-8650 2900);
DISPLAY INVISIBLE (-8650 2900);
FORCEADD TAP..1
R 2
(-7475 4750);
FORCEPROP 3 LASTPIN (-7425 4750) SIG_NAME M_G_CPU1_SB_CA<2>
J 0
(-7415 4760);
DISPLAY 0.659574 (-7415 4760);
PAINT MONO (-7415 4760);
DISPLAY INVISIBLE (-7415 4760);
FORCEPROP 1 LASTPIN (-7425 4750) BN 2
J 2
(-7413 4758);
DISPLAY 0.489362 (-7413 4758);
PAINT GREEN (-7413 4758);
FORCEPROP 2 LAST CDS_LIB mstr_standard
J 0
(-7475 4750);
DISPLAY 0.723404 (-7475 4750);
PAINT MONO (-7475 4750);
DISPLAY INVISIBLE (-7475 4750);
FORCEPROP 1 LAST BODY_TYPE PLUMBING
J 2
(-7475 4800);
DISPLAY 0.872340 (-7475 4800);
PAINT GREEN (-7475 4800);
DISPLAY INVISIBLE (-7475 4800);
FORCEPROP 1 LAST HDL_TAP TRUE
J 2
(-7800 4625);
DISPLAY 0.872340 (-7800 4625);
DISPLAY INVISIBLE (-7800 4625);
FORCEPROP 1 LAST PATH I80
J 2
(-7473 4750);
DISPLAY 0.872340 (-7473 4750);
PAINT GREEN (-7473 4750);
DISPLAY INVISIBLE (-7473 4750);
FORCEADD TAP..1
R 2
(-7475 4700);
FORCEPROP 3 LASTPIN (-7425 4700) SIG_NAME M_G_CPU1_SB_CA<1>
J 0
(-7415 4710);
DISPLAY 0.659574 (-7415 4710);
PAINT MONO (-7415 4710);
DISPLAY INVISIBLE (-7415 4710);
FORCEPROP 1 LASTPIN (-7425 4700) BN 1
J 2
(-7413 4708);
DISPLAY 0.489362 (-7413 4708);
PAINT GREEN (-7413 4708);
FORCEPROP 2 LAST CDS_LIB mstr_standard
J 0
(-7475 4700);
DISPLAY 0.723404 (-7475 4700);
PAINT MONO (-7475 4700);
DISPLAY INVISIBLE (-7475 4700);
FORCEPROP 1 LAST BODY_TYPE PLUMBING
J 2
(-7475 4750);
DISPLAY 0.872340 (-7475 4750);
PAINT GREEN (-7475 4750);
DISPLAY INVISIBLE (-7475 4750);
FORCEPROP 1 LAST HDL_TAP TRUE
J 2
(-7800 4575);
DISPLAY 0.872340 (-7800 4575);
DISPLAY INVISIBLE (-7800 4575);
FORCEPROP 1 LAST PATH I81
J 2
(-7473 4700);
DISPLAY 0.872340 (-7473 4700);
PAINT GREEN (-7473 4700);
DISPLAY INVISIBLE (-7473 4700);
FORCEADD TAP..1
R 2
(-7475 4650);
FORCEPROP 3 LASTPIN (-7425 4650) SIG_NAME M_G_CPU1_SB_CA<0>
J 0
(-7415 4660);
DISPLAY 0.659574 (-7415 4660);
PAINT MONO (-7415 4660);
DISPLAY INVISIBLE (-7415 4660);
FORCEPROP 1 LASTPIN (-7425 4650) BN 0
J 2
(-7413 4658);
DISPLAY 0.489362 (-7413 4658);
PAINT GREEN (-7413 4658);
FORCEPROP 2 LAST CDS_LIB mstr_standard
J 0
(-7475 4650);
DISPLAY 0.723404 (-7475 4650);
PAINT MONO (-7475 4650);
DISPLAY INVISIBLE (-7475 4650);
FORCEPROP 1 LAST BODY_TYPE PLUMBING
J 2
(-7475 4700);
DISPLAY 0.872340 (-7475 4700);
PAINT GREEN (-7475 4700);
DISPLAY INVISIBLE (-7475 4700);
FORCEPROP 1 LAST HDL_TAP TRUE
J 2
(-7800 4525);
DISPLAY 0.872340 (-7800 4525);
DISPLAY INVISIBLE (-7800 4525);
FORCEPROP 1 LAST PATH I82
J 2
(-7473 4650);
DISPLAY 0.872340 (-7473 4650);
PAINT GREEN (-7473 4650);
DISPLAY INVISIBLE (-7473 4650);
FORCEADD TAP..1
R 2
(-7475 4850);
FORCEPROP 3 LASTPIN (-7425 4850) SIG_NAME M_G_CPU1_SB_CA<4>
J 0
(-7415 4860);
DISPLAY 0.659574 (-7415 4860);
PAINT MONO (-7415 4860);
DISPLAY INVISIBLE (-7415 4860);
FORCEPROP 1 LASTPIN (-7425 4850) BN 4
J 2
(-7413 4858);
DISPLAY 0.489362 (-7413 4858);
PAINT GREEN (-7413 4858);
FORCEPROP 2 LAST CDS_LIB mstr_standard
J 0
(-7475 4850);
DISPLAY 0.723404 (-7475 4850);
PAINT MONO (-7475 4850);
DISPLAY INVISIBLE (-7475 4850);
FORCEPROP 1 LAST BODY_TYPE PLUMBING
J 2
(-7475 4900);
DISPLAY 0.872340 (-7475 4900);
PAINT GREEN (-7475 4900);
DISPLAY INVISIBLE (-7475 4900);
FORCEPROP 1 LAST HDL_TAP TRUE
J 2
(-7800 4725);
DISPLAY 0.872340 (-7800 4725);
DISPLAY INVISIBLE (-7800 4725);
FORCEPROP 1 LAST PATH I83
J 2
(-7473 4850);
DISPLAY 0.872340 (-7473 4850);
PAINT GREEN (-7473 4850);
DISPLAY INVISIBLE (-7473 4850);
FORCEADD TAP..1
R 2
(-7475 4800);
FORCEPROP 3 LASTPIN (-7425 4800) SIG_NAME M_G_CPU1_SB_CA<3>
J 0
(-7415 4810);
DISPLAY 0.659574 (-7415 4810);
PAINT MONO (-7415 4810);
DISPLAY INVISIBLE (-7415 4810);
FORCEPROP 1 LASTPIN (-7425 4800) BN 3
J 2
(-7413 4808);
DISPLAY 0.489362 (-7413 4808);
PAINT GREEN (-7413 4808);
FORCEPROP 2 LAST CDS_LIB mstr_standard
J 0
(-7475 4800);
DISPLAY 0.723404 (-7475 4800);
PAINT MONO (-7475 4800);
DISPLAY INVISIBLE (-7475 4800);
FORCEPROP 1 LAST BODY_TYPE PLUMBING
J 2
(-7475 4850);
DISPLAY 0.872340 (-7475 4850);
PAINT GREEN (-7475 4850);
DISPLAY INVISIBLE (-7475 4850);
FORCEPROP 1 LAST HDL_TAP TRUE
J 2
(-7800 4675);
DISPLAY 0.872340 (-7800 4675);
DISPLAY INVISIBLE (-7800 4675);
FORCEPROP 1 LAST PATH I84
J 2
(-7473 4800);
DISPLAY 0.872340 (-7473 4800);
PAINT GREEN (-7473 4800);
DISPLAY INVISIBLE (-7473 4800);
FORCEADD TAP..1
R 2
(-7475 4950);
FORCEPROP 3 LASTPIN (-7425 4950) SIG_NAME M_G_CPU1_SB_CA<6>
J 0
(-7415 4960);
DISPLAY 0.659574 (-7415 4960);
PAINT MONO (-7415 4960);
DISPLAY INVISIBLE (-7415 4960);
FORCEPROP 1 LASTPIN (-7425 4950) BN 6
J 2
(-7413 4958);
DISPLAY 0.489362 (-7413 4958);
PAINT GREEN (-7413 4958);
FORCEPROP 2 LAST CDS_LIB mstr_standard
J 0
(-7475 4950);
DISPLAY 0.723404 (-7475 4950);
PAINT MONO (-7475 4950);
DISPLAY INVISIBLE (-7475 4950);
FORCEPROP 1 LAST BODY_TYPE PLUMBING
J 2
(-7475 5000);
DISPLAY 0.872340 (-7475 5000);
PAINT GREEN (-7475 5000);
DISPLAY INVISIBLE (-7475 5000);
FORCEPROP 1 LAST HDL_TAP TRUE
J 2
(-7800 4825);
DISPLAY 0.872340 (-7800 4825);
DISPLAY INVISIBLE (-7800 4825);
FORCEPROP 1 LAST PATH I85
J 2
(-7473 4950);
DISPLAY 0.872340 (-7473 4950);
PAINT GREEN (-7473 4950);
DISPLAY INVISIBLE (-7473 4950);
FORCEADD TAP..1
R 2
(-7475 4900);
FORCEPROP 3 LASTPIN (-7425 4900) SIG_NAME M_G_CPU1_SB_CA<5>
J 0
(-7415 4910);
DISPLAY 0.659574 (-7415 4910);
PAINT MONO (-7415 4910);
DISPLAY INVISIBLE (-7415 4910);
FORCEPROP 1 LASTPIN (-7425 4900) BN 5
J 2
(-7413 4908);
DISPLAY 0.489362 (-7413 4908);
PAINT GREEN (-7413 4908);
FORCEPROP 2 LAST CDS_LIB mstr_standard
J 0
(-7475 4900);
DISPLAY 0.723404 (-7475 4900);
PAINT MONO (-7475 4900);
DISPLAY INVISIBLE (-7475 4900);
FORCEPROP 1 LAST BODY_TYPE PLUMBING
J 2
(-7475 4950);
DISPLAY 0.872340 (-7475 4950);
PAINT GREEN (-7475 4950);
DISPLAY INVISIBLE (-7475 4950);
FORCEPROP 1 LAST HDL_TAP TRUE
J 2
(-7800 4775);
DISPLAY 0.872340 (-7800 4775);
DISPLAY INVISIBLE (-7800 4775);
FORCEPROP 1 LAST PATH I86
J 2
(-7473 4900);
DISPLAY 0.872340 (-7473 4900);
PAINT GREEN (-7473 4900);
DISPLAY INVISIBLE (-7473 4900);
FORCEADD TAP..1
R 2
(-7475 5050);
FORCEPROP 3 LASTPIN (-7425 5050) SIG_NAME M_G_CPU1_SA_CA<0>
J 0
(-7415 5060);
DISPLAY 0.659574 (-7415 5060);
PAINT MONO (-7415 5060);
DISPLAY INVISIBLE (-7415 5060);
FORCEPROP 1 LASTPIN (-7425 5050) BN 0
J 2
(-7413 5058);
DISPLAY 0.489362 (-7413 5058);
PAINT GREEN (-7413 5058);
FORCEPROP 2 LAST CDS_LIB mstr_standard
J 0
(-7475 5050);
DISPLAY 0.723404 (-7475 5050);
PAINT MONO (-7475 5050);
DISPLAY INVISIBLE (-7475 5050);
FORCEPROP 1 LAST BODY_TYPE PLUMBING
J 2
(-7475 5100);
DISPLAY 0.872340 (-7475 5100);
PAINT GREEN (-7475 5100);
DISPLAY INVISIBLE (-7475 5100);
FORCEPROP 1 LAST HDL_TAP TRUE
J 2
(-7800 4925);
DISPLAY 0.872340 (-7800 4925);
DISPLAY INVISIBLE (-7800 4925);
FORCEPROP 1 LAST PATH I87
J 2
(-7473 5050);
DISPLAY 0.872340 (-7473 5050);
PAINT GREEN (-7473 5050);
DISPLAY INVISIBLE (-7473 5050);
FORCEADD TAP..1
R 2
(-7475 5150);
FORCEPROP 3 LASTPIN (-7425 5150) SIG_NAME M_G_CPU1_SA_CA<2>
J 0
(-7415 5160);
DISPLAY 0.659574 (-7415 5160);
PAINT MONO (-7415 5160);
DISPLAY INVISIBLE (-7415 5160);
FORCEPROP 1 LASTPIN (-7425 5150) BN 2
J 2
(-7413 5158);
DISPLAY 0.489362 (-7413 5158);
PAINT GREEN (-7413 5158);
FORCEPROP 2 LAST CDS_LIB mstr_standard
J 0
(-7475 5150);
DISPLAY 0.723404 (-7475 5150);
PAINT MONO (-7475 5150);
DISPLAY INVISIBLE (-7475 5150);
FORCEPROP 1 LAST BODY_TYPE PLUMBING
J 2
(-7475 5200);
DISPLAY 0.872340 (-7475 5200);
PAINT GREEN (-7475 5200);
DISPLAY INVISIBLE (-7475 5200);
FORCEPROP 1 LAST HDL_TAP TRUE
J 2
(-7800 5025);
DISPLAY 0.872340 (-7800 5025);
DISPLAY INVISIBLE (-7800 5025);
FORCEPROP 1 LAST PATH I88
J 2
(-7473 5150);
DISPLAY 0.872340 (-7473 5150);
PAINT GREEN (-7473 5150);
DISPLAY INVISIBLE (-7473 5150);
FORCEADD TAP..1
R 2
(-7475 5100);
FORCEPROP 3 LASTPIN (-7425 5100) SIG_NAME M_G_CPU1_SA_CA<1>
J 0
(-7415 5110);
DISPLAY 0.659574 (-7415 5110);
PAINT MONO (-7415 5110);
DISPLAY INVISIBLE (-7415 5110);
FORCEPROP 1 LASTPIN (-7425 5100) BN 1
J 2
(-7413 5108);
DISPLAY 0.489362 (-7413 5108);
PAINT GREEN (-7413 5108);
FORCEPROP 2 LAST CDS_LIB mstr_standard
J 0
(-7475 5100);
DISPLAY 0.723404 (-7475 5100);
PAINT MONO (-7475 5100);
DISPLAY INVISIBLE (-7475 5100);
FORCEPROP 1 LAST BODY_TYPE PLUMBING
J 2
(-7475 5150);
DISPLAY 0.872340 (-7475 5150);
PAINT GREEN (-7475 5150);
DISPLAY INVISIBLE (-7475 5150);
FORCEPROP 1 LAST HDL_TAP TRUE
J 2
(-7800 4975);
DISPLAY 0.872340 (-7800 4975);
DISPLAY INVISIBLE (-7800 4975);
FORCEPROP 1 LAST PATH I89
J 2
(-7473 5100);
DISPLAY 0.872340 (-7473 5100);
PAINT GREEN (-7473 5100);
DISPLAY INVISIBLE (-7473 5100);
FORCEADD OFFPAGE..1
(-8075 3050);
FORCEPROP 2 LAST $XR0 43 
J 0
(-8296 3050);
DISPLAY 0.638298 (-8296 3050);
PAINT MONO (-8296 3050);
FORCEPROP 2 LAST CDS_LIB mstr_standard
J 0
(-8075 3050);
DISPLAY 0.808511 (-8075 3050);
DISPLAY INVISIBLE (-8075 3050);
FORCEPROP 1 LAST OFFPAGE TRUE
J 0
(-7750 2925);
DISPLAY 0.872340 (-7750 2925);
PAINT GREEN (-7750 2925);
DISPLAY INVISIBLE (-7750 2925);
FORCEPROP 1 LAST COMMENT_BODY TRUE
J 0
(-7950 2950);
DISPLAY 0.872340 (-7950 2950);
PAINT GREEN (-7950 2950);
DISPLAY INVISIBLE (-7950 2950);
FORCEPROP 2 LAST PATH I9
J 0
(-8325 3100);
DISPLAY 1.021277 (-8325 3100);
DISPLAY INVISIBLE (-8325 3100);
FORCEADD TAP..1
R 2
(-7475 5200);
FORCEPROP 3 LASTPIN (-7425 5200) SIG_NAME M_G_CPU1_SA_CA<3>
J 0
(-7415 5210);
DISPLAY 0.659574 (-7415 5210);
PAINT MONO (-7415 5210);
DISPLAY INVISIBLE (-7415 5210);
FORCEPROP 1 LASTPIN (-7425 5200) BN 3
J 2
(-7413 5208);
DISPLAY 0.489362 (-7413 5208);
PAINT GREEN (-7413 5208);
FORCEPROP 2 LAST CDS_LIB mstr_standard
J 0
(-7475 5200);
DISPLAY 0.723404 (-7475 5200);
PAINT MONO (-7475 5200);
DISPLAY INVISIBLE (-7475 5200);
FORCEPROP 1 LAST BODY_TYPE PLUMBING
J 2
(-7475 5250);
DISPLAY 0.872340 (-7475 5250);
PAINT GREEN (-7475 5250);
DISPLAY INVISIBLE (-7475 5250);
FORCEPROP 1 LAST HDL_TAP TRUE
J 2
(-7800 5075);
DISPLAY 0.872340 (-7800 5075);
DISPLAY INVISIBLE (-7800 5075);
FORCEPROP 1 LAST PATH I90
J 2
(-7473 5200);
DISPLAY 0.872340 (-7473 5200);
PAINT GREEN (-7473 5200);
DISPLAY INVISIBLE (-7473 5200);
FORCEADD TAP..1
R 2
(-7475 5250);
FORCEPROP 3 LASTPIN (-7425 5250) SIG_NAME M_G_CPU1_SA_CA<4>
J 0
(-7415 5260);
DISPLAY 0.659574 (-7415 5260);
PAINT MONO (-7415 5260);
DISPLAY INVISIBLE (-7415 5260);
FORCEPROP 1 LASTPIN (-7425 5250) BN 4
J 2
(-7413 5258);
DISPLAY 0.489362 (-7413 5258);
PAINT GREEN (-7413 5258);
FORCEPROP 2 LAST CDS_LIB mstr_standard
J 0
(-7475 5250);
DISPLAY 0.723404 (-7475 5250);
PAINT MONO (-7475 5250);
DISPLAY INVISIBLE (-7475 5250);
FORCEPROP 1 LAST BODY_TYPE PLUMBING
J 2
(-7475 5300);
DISPLAY 0.872340 (-7475 5300);
PAINT GREEN (-7475 5300);
DISPLAY INVISIBLE (-7475 5300);
FORCEPROP 1 LAST HDL_TAP TRUE
J 2
(-7800 5125);
DISPLAY 0.872340 (-7800 5125);
DISPLAY INVISIBLE (-7800 5125);
FORCEPROP 1 LAST PATH I91
J 2
(-7473 5250);
DISPLAY 0.872340 (-7473 5250);
PAINT GREEN (-7473 5250);
DISPLAY INVISIBLE (-7473 5250);
FORCEADD TAP..1
R 2
(-7475 5300);
FORCEPROP 3 LASTPIN (-7425 5300) SIG_NAME M_G_CPU1_SA_CA<5>
J 0
(-7415 5310);
DISPLAY 0.659574 (-7415 5310);
PAINT MONO (-7415 5310);
DISPLAY INVISIBLE (-7415 5310);
FORCEPROP 1 LASTPIN (-7425 5300) BN 5
J 2
(-7413 5308);
DISPLAY 0.489362 (-7413 5308);
PAINT GREEN (-7413 5308);
FORCEPROP 2 LAST CDS_LIB mstr_standard
J 0
(-7475 5300);
DISPLAY 0.723404 (-7475 5300);
PAINT MONO (-7475 5300);
DISPLAY INVISIBLE (-7475 5300);
FORCEPROP 1 LAST BODY_TYPE PLUMBING
J 2
(-7475 5350);
DISPLAY 0.872340 (-7475 5350);
PAINT GREEN (-7475 5350);
DISPLAY INVISIBLE (-7475 5350);
FORCEPROP 1 LAST HDL_TAP TRUE
J 2
(-7800 5175);
DISPLAY 0.872340 (-7800 5175);
DISPLAY INVISIBLE (-7800 5175);
FORCEPROP 1 LAST PATH I92
J 2
(-7473 5300);
DISPLAY 0.872340 (-7473 5300);
PAINT GREEN (-7473 5300);
DISPLAY INVISIBLE (-7473 5300);
FORCEADD TAP..1
R 2
(-7475 5350);
FORCEPROP 3 LASTPIN (-7425 5350) SIG_NAME M_G_CPU1_SA_CA<6>
J 0
(-7415 5360);
DISPLAY 0.659574 (-7415 5360);
PAINT MONO (-7415 5360);
DISPLAY INVISIBLE (-7415 5360);
FORCEPROP 1 LASTPIN (-7425 5350) BN 6
J 2
(-7413 5358);
DISPLAY 0.489362 (-7413 5358);
PAINT GREEN (-7413 5358);
FORCEPROP 2 LAST CDS_LIB mstr_standard
J 0
(-7475 5350);
DISPLAY 0.723404 (-7475 5350);
PAINT MONO (-7475 5350);
DISPLAY INVISIBLE (-7475 5350);
FORCEPROP 1 LAST BODY_TYPE PLUMBING
J 2
(-7475 5400);
DISPLAY 0.872340 (-7475 5400);
PAINT GREEN (-7475 5400);
DISPLAY INVISIBLE (-7475 5400);
FORCEPROP 1 LAST HDL_TAP TRUE
J 2
(-7800 5225);
DISPLAY 0.872340 (-7800 5225);
DISPLAY INVISIBLE (-7800 5225);
FORCEPROP 1 LAST PATH I93
J 2
(-7473 5350);
DISPLAY 0.872340 (-7473 5350);
PAINT GREEN (-7473 5350);
DISPLAY INVISIBLE (-7473 5350);
FORCEADD TAP..1
(-5775 4000);
FORCEPROP 3 LASTPIN (-5825 4000) SIG_NAME M_G_CPU1_SA_DQ<4>
J 0
(-5815 4010);
DISPLAY 0.659574 (-5815 4010);
PAINT MONO (-5815 4010);
DISPLAY INVISIBLE (-5815 4010);
FORCEPROP 1 LASTPIN (-5825 4000) BN 4
J 0
(-5837 4008);
DISPLAY 0.489362 (-5837 4008);
PAINT GREEN (-5837 4008);
FORCEPROP 2 LAST CDS_LIB mstr_standard
J 0
(-5775 4000);
DISPLAY 0.723404 (-5775 4000);
PAINT MONO (-5775 4000);
DISPLAY INVISIBLE (-5775 4000);
FORCEPROP 1 LAST BODY_TYPE PLUMBING
J 0
(-5775 4050);
DISPLAY 0.872340 (-5775 4050);
PAINT GREEN (-5775 4050);
DISPLAY INVISIBLE (-5775 4050);
FORCEPROP 1 LAST HDL_TAP TRUE
J 0
(-5450 3875);
DISPLAY 0.872340 (-5450 3875);
DISPLAY INVISIBLE (-5450 3875);
FORCEPROP 1 LAST PATH I94
J 0
(-5777 4000);
DISPLAY 0.872340 (-5777 4000);
PAINT GREEN (-5777 4000);
DISPLAY INVISIBLE (-5777 4000);
FORCEADD TAP..1
(-5775 3900);
FORCEPROP 3 LASTPIN (-5825 3900) SIG_NAME M_G_CPU1_SA_DQ<2>
J 0
(-5815 3910);
DISPLAY 0.659574 (-5815 3910);
PAINT MONO (-5815 3910);
DISPLAY INVISIBLE (-5815 3910);
FORCEPROP 1 LASTPIN (-5825 3900) BN 2
J 0
(-5837 3908);
DISPLAY 0.489362 (-5837 3908);
PAINT GREEN (-5837 3908);
FORCEPROP 2 LAST CDS_LIB mstr_standard
J 0
(-5775 3900);
DISPLAY 0.723404 (-5775 3900);
PAINT MONO (-5775 3900);
DISPLAY INVISIBLE (-5775 3900);
FORCEPROP 1 LAST BODY_TYPE PLUMBING
J 0
(-5775 3950);
DISPLAY 0.872340 (-5775 3950);
PAINT GREEN (-5775 3950);
DISPLAY INVISIBLE (-5775 3950);
FORCEPROP 1 LAST HDL_TAP TRUE
J 0
(-5450 3775);
DISPLAY 0.872340 (-5450 3775);
DISPLAY INVISIBLE (-5450 3775);
FORCEPROP 1 LAST PATH I95
J 0
(-5777 3900);
DISPLAY 0.872340 (-5777 3900);
PAINT GREEN (-5777 3900);
DISPLAY INVISIBLE (-5777 3900);
FORCEADD TAP..1
(-5775 3950);
FORCEPROP 3 LASTPIN (-5825 3950) SIG_NAME M_G_CPU1_SA_DQ<3>
J 0
(-5815 3960);
DISPLAY 0.659574 (-5815 3960);
PAINT MONO (-5815 3960);
DISPLAY INVISIBLE (-5815 3960);
FORCEPROP 1 LASTPIN (-5825 3950) BN 3
J 0
(-5837 3958);
DISPLAY 0.489362 (-5837 3958);
PAINT GREEN (-5837 3958);
FORCEPROP 2 LAST CDS_LIB mstr_standard
J 0
(-5775 3950);
DISPLAY 0.723404 (-5775 3950);
PAINT MONO (-5775 3950);
DISPLAY INVISIBLE (-5775 3950);
FORCEPROP 1 LAST BODY_TYPE PLUMBING
J 0
(-5775 4000);
DISPLAY 0.872340 (-5775 4000);
PAINT GREEN (-5775 4000);
DISPLAY INVISIBLE (-5775 4000);
FORCEPROP 1 LAST HDL_TAP TRUE
J 0
(-5450 3825);
DISPLAY 0.872340 (-5450 3825);
DISPLAY INVISIBLE (-5450 3825);
FORCEPROP 1 LAST PATH I96
J 0
(-5777 3950);
DISPLAY 0.872340 (-5777 3950);
PAINT GREEN (-5777 3950);
DISPLAY INVISIBLE (-5777 3950);
FORCEADD TAP..1
(-5775 3800);
FORCEPROP 3 LASTPIN (-5825 3800) SIG_NAME M_G_CPU1_SA_DQ<0>
J 0
(-5815 3810);
DISPLAY 0.659574 (-5815 3810);
PAINT MONO (-5815 3810);
DISPLAY INVISIBLE (-5815 3810);
FORCEPROP 1 LASTPIN (-5825 3800) BN 0
J 0
(-5837 3808);
DISPLAY 0.489362 (-5837 3808);
PAINT GREEN (-5837 3808);
FORCEPROP 2 LAST CDS_LIB mstr_standard
J 0
(-5775 3800);
DISPLAY 0.723404 (-5775 3800);
PAINT MONO (-5775 3800);
DISPLAY INVISIBLE (-5775 3800);
FORCEPROP 1 LAST BODY_TYPE PLUMBING
J 0
(-5775 3850);
DISPLAY 0.872340 (-5775 3850);
PAINT GREEN (-5775 3850);
DISPLAY INVISIBLE (-5775 3850);
FORCEPROP 1 LAST HDL_TAP TRUE
J 0
(-5450 3675);
DISPLAY 0.872340 (-5450 3675);
DISPLAY INVISIBLE (-5450 3675);
FORCEPROP 1 LAST PATH I97
J 0
(-5777 3800);
DISPLAY 0.872340 (-5777 3800);
PAINT GREEN (-5777 3800);
DISPLAY INVISIBLE (-5777 3800);
FORCEADD TAP..1
(-5775 3850);
FORCEPROP 3 LASTPIN (-5825 3850) SIG_NAME M_G_CPU1_SA_DQ<1>
J 0
(-5815 3860);
DISPLAY 0.659574 (-5815 3860);
PAINT MONO (-5815 3860);
DISPLAY INVISIBLE (-5815 3860);
FORCEPROP 1 LASTPIN (-5825 3850) BN 1
J 0
(-5837 3858);
DISPLAY 0.489362 (-5837 3858);
PAINT GREEN (-5837 3858);
FORCEPROP 2 LAST CDS_LIB mstr_standard
J 0
(-5775 3850);
DISPLAY 0.723404 (-5775 3850);
PAINT MONO (-5775 3850);
DISPLAY INVISIBLE (-5775 3850);
FORCEPROP 1 LAST BODY_TYPE PLUMBING
J 0
(-5775 3900);
DISPLAY 0.872340 (-5775 3900);
PAINT GREEN (-5775 3900);
DISPLAY INVISIBLE (-5775 3900);
FORCEPROP 1 LAST HDL_TAP TRUE
J 0
(-5450 3725);
DISPLAY 0.872340 (-5450 3725);
DISPLAY INVISIBLE (-5450 3725);
FORCEPROP 1 LAST PATH I98
J 0
(-5777 3850);
DISPLAY 0.872340 (-5777 3850);
PAINT GREEN (-5777 3850);
DISPLAY INVISIBLE (-5777 3850);
FORCEADD TAP..1
(-5775 4150);
FORCEPROP 3 LASTPIN (-5825 4150) SIG_NAME M_G_CPU1_SA_DQ<7>
J 0
(-5815 4160);
DISPLAY 0.659574 (-5815 4160);
PAINT MONO (-5815 4160);
DISPLAY INVISIBLE (-5815 4160);
FORCEPROP 1 LASTPIN (-5825 4150) BN 7
J 0
(-5837 4158);
DISPLAY 0.489362 (-5837 4158);
PAINT GREEN (-5837 4158);
FORCEPROP 2 LAST CDS_LIB mstr_standard
J 0
(-5775 4150);
DISPLAY 0.723404 (-5775 4150);
PAINT MONO (-5775 4150);
DISPLAY INVISIBLE (-5775 4150);
FORCEPROP 1 LAST BODY_TYPE PLUMBING
J 0
(-5775 4200);
DISPLAY 0.872340 (-5775 4200);
PAINT GREEN (-5775 4200);
DISPLAY INVISIBLE (-5775 4200);
FORCEPROP 1 LAST HDL_TAP TRUE
J 0
(-5450 4025);
DISPLAY 0.872340 (-5450 4025);
DISPLAY INVISIBLE (-5450 4025);
FORCEPROP 1 LAST PATH I99
J 0
(-5777 4150);
DISPLAY 0.872340 (-5777 4150);
PAINT GREEN (-5777 4150);
DISPLAY INVISIBLE (-5777 4150);
FORCEADD DNS..2
(-8625 2275);
PAINT RED (-8625 2275);
FORCEPROP 2 LAST CDS_LIB mstr_misc
J 0
(-8625 2275);
DISPLAY INVISIBLE (-8625 2275);
FORCEPROP 1 LAST COMMENT_BODY TRUE
R 1
J 0
(-8550 2050);
DISPLAY 0.872340 (-8550 2050);
PAINT PEACH (-8550 2050);
DISPLAY INVISIBLE (-8550 2050);
FORCEADD DNS..2
(-8250 2250);
PAINT RED (-8250 2250);
FORCEPROP 2 LAST CDS_LIB mstr_misc
J 0
(-8250 2250);
DISPLAY INVISIBLE (-8250 2250);
FORCEPROP 1 LAST COMMENT_BODY TRUE
R 1
J 0
(-8175 2025);
DISPLAY 0.872340 (-8175 2025);
PAINT PEACH (-8175 2025);
DISPLAY INVISIBLE (-8175 2025);
FORCEADD QUANTA_TITLE_BLOCK_C..1
(0 0);
FORCEPROP 0 LAST CDS_CON_LAST_MODIFIED Thu Sep 14 16:12:12 2023
J 0
(-1885 15);
DISPLAY INVISIBLE (-1885 15);
FORCEPROP 1 LAST CUSTOM_TXT_CDS <CON_LAST_MODIFIED>
J 0
(-1885 15);
DISPLAY 0.978723 (-1885 15);
FORCEPROP 2 LAST CUSTOM_TXT_CDS <XR_PAGE_TITLE>
J 0
(-7890 5250);
DISPLAY 0.638298 (-7890 5250);
PAINT PINK (-7890 5250);
DISPLAY INVISIBLE (-7890 5250);
FORCEPROP 1 LAST CUSTOM_TXT_CDS <NAME_2>
J 0
(-3175 50);
FORCEPROP 1 LAST CUSTOM_TXT_CDS <NAME_1>
J 0
(-3175 175);
FORCEPROP 1 LAST CUSTOM_TXT_CDS <Q_NUMBER>
J 0
(-1403 103);
DISPLAY 1.212766 (-1403 103);
FORCEPROP 1 LAST CUSTOM_TXT_CDS <Q_PROJ>
J 0
(-2382 102);
DISPLAY 1.212766 (-2382 102);
FORCEPROP 1 LAST CUSTOM_TXT_CDS <Q_REV>
J 0
(-184 103);
DISPLAY 1.212766 (-184 103);
FORCEPROP 1 LAST CUSTOM_TXT_CDS <CON_PAGE_NUM> OF <CON_TOTAL_PAGES>
J 0
(-446 18);
DISPLAY 0.978723 (-446 18);
FORCEPROP 1 LAST Q_TITLE DDR5 - CPU1 CHG
J 0
(-9325 50);
DISPLAY 2.446809 (-9325 50);
PAINT GREEN (-9325 50);
FORCEPROP 2 LAST CDS_LIB pure_quanta
J 0
(0 0);
DISPLAY INVISIBLE (0 0);
FORCEPROP 1 LAST CDS_LMAN_SYM_OUTLINE -9475,6775,100,-125
J 0
(0 0);
DISPLAY 0.468085 (0 0);
PAINT GREEN (0 0);
DISPLAY INVISIBLE (0 0);
FORCEPROP 2 LAST PAGE_BORDER TRUE
J 0
(-7890 5250);
DISPLAY 0.638298 (-7890 5250);
PAINT PINK (-7890 5250);
DISPLAY INVISIBLE (-7890 5250);
FORCEPROP 2 LAST CDS_XR_PAGE_TITLE CR-104 : @T6G_MB_LIB.T6G(SCH_1):PAGE104
J 0
(-7890 5250);
DISPLAY 0.638298 (-7890 5250);
PAINT PINK (-7890 5250);
DISPLAY INVISIBLE (-7890 5250);
FORCEPROP 1 LAST Q_DEPT BU9
J 1
(-3763 49);
DISPLAY 1.957447 (-3763 49);
PAINT GREEN (-3763 49);
DISPLAY INVISIBLE (-3763 49);
FORCEPROP 1 LAST COMMENT_BODY TRUE
J 0
(12 -13);
DISPLAY 0.978723 (12 -13);
PAINT GREEN (12 -13);
DISPLAY INVISIBLE (12 -13);
FORCEADD DNS..2
(-2300 1325);
PAINT RED (-2300 1325);
FORCEPROP 2 LAST CDS_LIB mstr_misc
J 0
(-2300 1325);
DISPLAY INVISIBLE (-2300 1325);
FORCEPROP 1 LAST COMMENT_BODY TRUE
R 1
J 0
(-2225 1100);
DISPLAY 0.872340 (-2225 1100);
PAINT PEACH (-2225 1100);
DISPLAY INVISIBLE (-2225 1100);
FORCEADD DNS..2
(-4250 1175);
PAINT RED (-4250 1175);
FORCEPROP 2 LAST CDS_LIB mstr_misc
J 0
(-4250 1175);
DISPLAY INVISIBLE (-4250 1175);
FORCEPROP 1 LAST COMMENT_BODY TRUE
R 1
J 0
(-4175 950);
DISPLAY 0.872340 (-4175 950);
PAINT PEACH (-4175 950);
DISPLAY INVISIBLE (-4175 950);
WIRE 17 -1 (-7525 3975)(-7525 4000);
WIRE 17 -1 (-7525 3975)(-7525 3925);
WIRE 17 -1 (-7525 4000)(-8025 4000);
FORCEPROP 2 LAST SIG_NAME M_G_CPU1_SA_CB<7:0>
J 0
(-8025 4010);
DISPLAY 0.489362 (-8025 4010);
WIRE 17 -1 (-7525 5225)(-7525 5275);
WIRE 17 -1 (-7525 5175)(-7525 5225);
WIRE 17 -1 (-7525 5275)(-7525 5325);
WIRE 17 -1 (-7525 5325)(-7525 5375);
WIRE 17 -1 (-7525 5125)(-7525 5175);
WIRE 17 -1 (-7525 5075)(-7525 5125);
WIRE 17 -1 (-7525 5375)(-7525 5400);
WIRE 17 -1 (-7525 5400)(-8025 5400);
FORCEPROP 2 LAST SIG_NAME M_G_CPU1_SA_CA<6:0>
J 0
(-8025 5410);
DISPLAY 0.489362 (-8025 5410);
WIRE 17 -1 (-3200 3425)(-3200 3400);
WIRE 17 -1 (-3200 3425)(-2500 3425);
FORCEPROP 2 LAST SIG_NAME M_G_CPU1_SB_DQS_DP<9:0>
J 2
(-2500 3435);
DISPLAY 0.489362 (-2500 3435);
WIRE 17 -1 (-3000 3375)(-3000 3350);
WIRE 17 -1 (-3000 3375)(-2500 3375);
FORCEPROP 2 LAST SIG_NAME M_G_CPU1_SB_DQS_DN<9:0>
J 2
(-2500 3385);
DISPLAY 0.489362 (-2500 3385);
WIRE 17 -1 (-3200 4475)(-3200 4450);
WIRE 17 -1 (-3200 4475)(-2500 4475);
FORCEPROP 2 LAST SIG_NAME M_G_CPU1_SA_DQS_DP<9:0>
J 0
(-3035 4485);
DISPLAY 0.489362 (-3035 4485);
WIRE 17 -1 (-3000 4425)(-3000 4400);
WIRE 17 -1 (-3000 4425)(-2500 4425);
FORCEPROP 2 LAST SIG_NAME M_G_CPU1_SA_DQS_DN<9:0>
J 0
(-3035 4435);
DISPLAY 0.489362 (-3035 4435);
WIRE 17 -1 (-3200 4450)(-3200 4350);
WIRE 17 -1 (-3200 4350)(-3200 4250);
WIRE 17 -1 (-3200 4250)(-3200 4150);
WIRE 17 -1 (-3000 4400)(-3000 4300);
WIRE 17 -1 (-3000 4300)(-3000 4200);
WIRE 17 -1 (-3000 4200)(-3000 4100);
WIRE 17 -1 (-3000 3250)(-3000 3150);
WIRE 17 -1 (-3000 3350)(-3000 3250);
WIRE 17 -1 (-3000 3150)(-3000 3050);
WIRE 17 -1 (-3000 3050)(-3000 2950);
WIRE 17 -1 (-3200 4150)(-3200 4050);
WIRE 17 -1 (-3200 3200)(-3200 3100);
WIRE 17 -1 (-3200 3300)(-3200 3200);
WIRE 17 -1 (-3200 3100)(-3200 3000);
WIRE 17 -1 (-3200 2900)(-3200 3000);
WIRE 17 -1 (-3200 3400)(-3200 3300);
WIRE 17 -1 (-3200 2800)(-3200 2900);
WIRE 17 -1 (-3200 2700)(-3200 2800);
WIRE 17 -1 (-3000 2850)(-3000 2950);
WIRE 17 -1 (-3000 2750)(-3000 2850);
WIRE 17 -1 (-3000 2650)(-3000 2750);
WIRE 17 -1 (-3000 4100)(-3000 4000);
WIRE 17 -1 (-3000 3900)(-3000 4000);
WIRE 17 -1 (-3000 3800)(-3000 3900);
WIRE 17 -1 (-3000 3700)(-3000 3800);
WIRE 17 -1 (-3200 2700)(-3200 2600);
WIRE 17 -1 (-3000 2650)(-3000 2550);
WIRE 17 -1 (-3200 3950)(-3200 4050);
WIRE 17 -1 (-3200 3850)(-3200 3950);
WIRE 17 -1 (-3200 3750)(-3200 3850);
WIRE 17 -1 (-3200 3750)(-3200 3650);
WIRE 17 -1 (-3000 3700)(-3000 3600);
WIRE 17 -1 (-3200 2600)(-3200 2500);
WIRE 17 -1 (-3000 2550)(-3000 2450);
WIRE 17 -1 (-3200 3650)(-3200 3550);
WIRE 17 -1 (-3000 3600)(-3000 3500);
WIRE 17 -1 (-5725 2175)(-5725 2225);
WIRE 17 -1 (-5725 2225)(-5725 2275);
WIRE 17 -1 (-5725 2275)(-5725 2325);
WIRE 17 -1 (-5725 2325)(-5725 2375);
WIRE 17 -1 (-5725 2425)(-5725 2375);
WIRE 17 -1 (-5725 2475)(-5725 2425);
WIRE 17 -1 (-5725 2525)(-5725 2475);
WIRE 17 -1 (-5725 2575)(-5725 2525);
WIRE 17 -1 (-5725 2625)(-5725 2575);
WIRE 17 -1 (-5725 2675)(-5725 2625);
WIRE 17 -1 (-5725 2725)(-5725 2675);
WIRE 17 -1 (-5725 2775)(-5725 2725);
WIRE 17 -1 (-5725 2775)(-5725 2825);
WIRE 17 -1 (-5725 2825)(-5725 2875);
WIRE 17 -1 (-5725 2875)(-5725 2925);
WIRE 17 -1 (-5725 2925)(-5725 2975);
WIRE 17 -1 (-5725 3025)(-5725 2975);
WIRE 17 -1 (-5725 3075)(-5725 3025);
WIRE 17 -1 (-5725 3125)(-5725 3075);
WIRE 17 -1 (-5725 3175)(-5725 3125);
WIRE 17 -1 (-5725 3225)(-5725 3175);
WIRE 17 -1 (-5725 3275)(-5725 3225);
WIRE 17 -1 (-5725 3325)(-5725 3275);
WIRE 17 -1 (-5725 3375)(-5725 3325);
WIRE 17 -1 (-5725 3425)(-5725 3375);
WIRE 17 -1 (-5725 3475)(-5725 3425);
WIRE 17 -1 (-5725 3525)(-5725 3475);
WIRE 17 -1 (-5725 3575)(-5725 3525);
WIRE 17 -1 (-5725 3625)(-5725 3575);
WIRE 17 -1 (-5725 3675)(-5725 3625);
WIRE 17 -1 (-5725 3725)(-5725 3675);
WIRE 17 -1 (-5725 3750)(-5725 3725);
WIRE 17 -1 (-5725 3750)(-5225 3750);
FORCEPROP 2 LAST SIG_NAME M_G_CPU1_SB_DQ<31:0>
J 2
(-5225 3760);
DISPLAY 0.489362 (-5225 3760);
WIRE 17 -1 (-5725 3825)(-5725 3875);
WIRE 17 -1 (-5725 3875)(-5725 3925);
WIRE 17 -1 (-5725 3925)(-5725 3975);
WIRE 17 -1 (-5725 3975)(-5725 4025);
WIRE 17 -1 (-5725 4075)(-5725 4025);
WIRE 17 -1 (-5725 4125)(-5725 4075);
WIRE 17 -1 (-5725 4175)(-5725 4125);
WIRE 17 -1 (-5725 4225)(-5725 4175);
WIRE 17 -1 (-5725 4275)(-5725 4225);
WIRE 17 -1 (-5725 4325)(-5725 4275);
WIRE 17 -1 (-5725 4375)(-5725 4325);
WIRE 17 -1 (-5725 4425)(-5725 4375);
WIRE 17 -1 (-5725 4425)(-5725 4475);
WIRE 17 -1 (-5725 4475)(-5725 4525);
WIRE 17 -1 (-5725 4525)(-5725 4575);
WIRE 17 -1 (-5725 4575)(-5725 4625);
WIRE 17 -1 (-5725 4675)(-5725 4625);
WIRE 17 -1 (-5725 4725)(-5725 4675);
WIRE 17 -1 (-5725 4775)(-5725 4725);
WIRE 17 -1 (-5725 4825)(-5725 4775);
WIRE 17 -1 (-5725 4875)(-5725 4825);
WIRE 17 -1 (-5725 4925)(-5725 4875);
WIRE 17 -1 (-5725 4975)(-5725 4925);
WIRE 17 -1 (-5725 5025)(-5725 4975);
WIRE 17 -1 (-5725 5075)(-5725 5025);
WIRE 17 -1 (-5725 5125)(-5725 5075);
WIRE 17 -1 (-5725 5175)(-5725 5125);
WIRE 17 -1 (-5725 5225)(-5725 5175);
WIRE 17 -1 (-5725 5275)(-5725 5225);
WIRE 17 -1 (-5725 5325)(-5725 5275);
WIRE 17 -1 (-5725 5375)(-5725 5325);
WIRE 17 -1 (-5725 5400)(-5725 5375);
WIRE 17 -1 (-5725 5400)(-5225 5400);
FORCEPROP 2 LAST SIG_NAME M_G_CPU1_SA_DQ<31:0>
J 2
(-5225 5410);
DISPLAY 0.489362 (-5225 5410);
WIRE 17 -1 (-7525 3225)(-7525 3275);
WIRE 17 -1 (-7525 3175)(-7525 3225);
WIRE 17 -1 (-7525 3275)(-7525 3325);
WIRE 17 -1 (-7525 3325)(-7525 3375);
WIRE 17 -1 (-7525 3425)(-7525 3375);
WIRE 17 -1 (-7525 3425)(-7525 3475);
WIRE 17 -1 (-7525 3525)(-7525 3475);
WIRE 17 -1 (-7525 3525)(-7525 3550);
WIRE 17 -1 (-7525 3550)(-8025 3550);
FORCEPROP 2 LAST SIG_NAME M_G_CPU1_SB_CB<7:0>
J 0
(-8025 3560);
DISPLAY 0.489362 (-8025 3560);
WIRE 17 -1 (-7525 3625)(-7525 3675);
WIRE 17 -1 (-7525 3675)(-7525 3725);
WIRE 17 -1 (-7525 3725)(-7525 3775);
WIRE 17 -1 (-7525 3775)(-7525 3825);
WIRE 17 -1 (-7525 3875)(-7525 3825);
WIRE 17 -1 (-7525 3875)(-7525 3925);
WIRE 17 -1 (-7525 4925)(-7525 4975);
WIRE 17 -1 (-7525 4875)(-7525 4925);
WIRE 17 -1 (-7525 4975)(-7525 5000);
WIRE 17 -1 (-7525 5000)(-8025 5000);
FORCEPROP 2 LAST SIG_NAME M_G_CPU1_SB_CA<6:0>
J 0
(-8025 5010);
DISPLAY 0.489362 (-8025 5010);
WIRE 17 -1 (-7525 4825)(-7525 4875);
WIRE 17 -1 (-7525 4775)(-7525 4825);
WIRE 17 -1 (-7525 4725)(-7525 4775);
WIRE 17 -1 (-7525 4675)(-7525 4725);
WIRE 16 -1 (-6200 950)(-6200 1025);
WIRE 16 -1 (-8675 3025)(-8675 3100);
WIRE 16 -1 (-8525 2350)(-8525 2375);
WIRE 16 -1 (-8275 2350)(-8275 2375);
WIRE 16 -1 (-8975 1475)(-8975 1625);
WIRE 16 -1 (-7225 3000)(-8025 3000);
FORCEPROP 2 LAST SIG_NAME M_G_CPU1_ALERT_N
J 0
(-8010 3010);
DISPLAY 0.489362 (-8010 3010);
WIRE 16 -1 (-7225 2800)(-7800 2800);
FORCEPROP 2 LAST SIG_NAME I3C_SPD_DDRG_CPU1_SDA
J 0
(-7710 2810);
DISPLAY 0.446809 (-7710 2810);
FORCEPROP 2 LASTPROP $XRERR UNIQUE?
J 0
(-7950 2810);
DISPLAY 0.638298 (-7950 2810);
PAINT MONO (-7950 2810);
DISPLAY INVISIBLE (-7950 2810);
WIRE 16 -1 (-8575 2900)(-7225 2900);
WIRE 16 -1 (-8575 3325)(-8575 2900);
WIRE 16 -1 (-8575 3375)(-8575 3325);
WIRE 16 -1 (-8675 3325)(-8575 3325);
WIRE 16 -1 (-8675 3300)(-8675 3325);
WIRE 16 -1 (-7225 2850)(-8325 2850);
FORCEPROP 2 LAST SIG_NAME PD_CHG_CPU1_DIMM0_SAA
J 0
(-8325 2860);
DISPLAY 0.489362 (-8325 2860);
WIRE 16 -1 (-7225 3050)(-8025 3050);
FORCEPROP 2 LAST SIG_NAME M_G_CPU1_RESET_N
J 0
(-8010 3060);
DISPLAY 0.489362 (-8010 3060);
WIRE 16 -1 (-8275 2150)(-8275 2100);
WIRE 16 -1 (-8025 2100)(-8275 2100);
WIRE 16 -1 (-8275 2100)(-8300 2100);
WIRE 16 -1 (-8025 2100)(-8025 2500);
WIRE 16 -1 (-7225 2500)(-8025 2500);
FORCEPROP 2 LAST SIG_NAME PWRGD_CHG_CPU1_DIMM0
J 0
(-7850 2510);
DISPLAY 0.489362 (-7850 2510);
FORCEPROP 2 LASTPROP $XRERR UNIQUE?
J 0
(-8090 2510);
DISPLAY 0.638298 (-8090 2510);
PAINT MONO (-8090 2510);
DISPLAY INVISIBLE (-8090 2510);
WIRE 16 -1 (-7225 3150)(-7425 3150);
WIRE 16 -1 (-7225 3200)(-7425 3200);
WIRE 16 -1 (-7325 2750)(-7325 2575);
WIRE 16 -1 (-7225 2750)(-7325 2750);
FORCEPROP 2 LAST SIG_NAME I3C_SPD_DDRG_CPU1_SCL
J 0
(-7710 2760);
DISPLAY 0.446809 (-7710 2760);
FORCEPROP 2 LASTPROP $XRERR UNIQUE?
J 0
(-7950 2760);
DISPLAY 0.638298 (-7950 2760);
PAINT MONO (-7950 2760);
DISPLAY INVISIBLE (-7950 2760);
WIRE 16 -1 (-7325 2575)(-7425 2575);
WIRE 16 -1 (-7225 3450)(-7425 3450);
WIRE 16 -1 (-6025 2900)(-5825 2900);
WIRE 16 -1 (-5825 2850)(-6025 2850);
WIRE 16 -1 (-2450 1200)(-2625 1200);
WIRE 16 -1 (-2625 1200)(-2625 750);
WIRE 16 -1 (-2625 750)(-2525 750);
WIRE 16 -1 (-3600 750)(-2625 750);
FORCEPROP 2 LAST SIG_NAME PWRGD_CHGL_CPU1_R1
J 0
(-3410 760);
DISPLAY 0.680851 (-3410 760);
FORCEPROP 2 LASTPROP $XRERR UNIQUE?
J 0
(-3650 760);
DISPLAY 0.638298 (-3650 760);
PAINT MONO (-3650 760);
DISPLAY INVISIBLE (-3650 760);
WIRE 16 -1 (-3600 1225)(-3600 750);
WIRE 16 -1 (-3750 750)(-3600 750);
WIRE 16 -1 (-4175 1225)(-3600 1225);
WIRE 16 -1 (-8975 1275)(-8975 975);
WIRE 16 -1 (-8975 975)(-8000 975);
FORCEPROP 2 LAST SIG_NAME PWRGD_CHGL_CPU1
J 0
(-8710 985);
DISPLAY 0.680851 (-8710 985);
WIRE 16 -1 (-6200 1300)(-6200 1225);
WIRE 16 -1 (-6200 1300)(-6925 1300);
FORCEPROP 2 LAST SIG_NAME PD_CHG_CPU1_DIMM0_SAA
J 0
(-6910 1310);
DISPLAY 0.489362 (-6910 1310);
WIRE 16 -1 (-4700 750)(-3950 750);
FORCEPROP 2 LAST SIG_NAME PWRGD_CHGL_CPU1
J 0
(-4560 760);
DISPLAY 0.680851 (-4560 760);
WIRE 16 -1 (-4875 1225)(-4375 1225);
WIRE 16 -1 (-4875 1375)(-4875 1225);
WIRE 16 -1 (-1650 1275)(-1650 1200);
WIRE 16 -1 (-1650 1200)(-2200 1200);
WIRE 16 -1 (-2250 6075)(-2125 6075);
WIRE 16 -1 (-2250 6075)(-2250 5975);
WIRE 16 -1 (-2250 6075)(-2825 6075);
WIRE 16 -1 (-2125 5275)(-2125 6075);
WIRE 16 -1 (-1925 5275)(-2125 5275);
WIRE 16 -1 (-2125 5225)(-2125 5275);
WIRE 16 -1 (-2825 5975)(-2825 6075);
WIRE 16 -1 (-2825 6075)(-2825 6150);
WIRE 16 -1 (-1925 5225)(-2125 5225);
WIRE 16 -1 (-2125 5175)(-2125 5225);
WIRE 16 -1 (-1925 5175)(-2125 5175);
WIRE 16 -1 (-2250 5650)(-2250 5775);
WIRE 16 -1 (-2250 5650)(-2825 5650);
WIRE 16 -1 (-2825 5650)(-2825 5775);
WIRE 16 -1 (-2825 5650)(-2825 5575);
WIRE 16 -1 (-525 2125)(-525 2025);
WIRE 16 -1 (-525 2175)(-525 2125);
WIRE 16 -1 (-525 2125)(-725 2125);
WIRE 16 -1 (-525 2025)(-525 1975);
WIRE 16 -1 (-525 2025)(-725 2025);
WIRE 16 -1 (-525 1975)(-525 1925);
WIRE 16 -1 (-525 1975)(-725 1975);
WIRE 16 -1 (-525 2225)(-525 2175);
WIRE 16 -1 (-525 2175)(-725 2175);
WIRE 16 -1 (-525 2275)(-525 2225);
WIRE 16 -1 (-525 2225)(-725 2225);
WIRE 16 -1 (-525 1925)(-725 1925);
WIRE 16 -1 (-525 1925)(-525 1725);
WIRE 16 -1 (-525 2325)(-525 2275);
WIRE 16 -1 (-525 2275)(-725 2275);
WIRE 16 -1 (-525 2375)(-525 2325);
WIRE 16 -1 (-525 2325)(-725 2325);
WIRE 16 -1 (-525 2425)(-525 2375);
WIRE 16 -1 (-525 2375)(-725 2375);
WIRE 16 -1 (-525 2475)(-525 2425);
WIRE 16 -1 (-525 2425)(-725 2425);
WIRE 16 -1 (-525 2525)(-525 2475);
WIRE 16 -1 (-525 2475)(-725 2475);
WIRE 16 -1 (-525 2575)(-525 2525);
WIRE 16 -1 (-525 2525)(-725 2525);
WIRE 16 -1 (-525 2625)(-525 2575);
WIRE 16 -1 (-525 2575)(-725 2575);
WIRE 16 -1 (-525 2675)(-525 2625);
WIRE 16 -1 (-525 2625)(-725 2625);
WIRE 16 -1 (-525 2725)(-525 2675);
WIRE 16 -1 (-525 2675)(-725 2675);
WIRE 16 -1 (-525 2775)(-525 2725);
WIRE 16 -1 (-525 2725)(-725 2725);
WIRE 16 -1 (-525 2825)(-525 2775);
WIRE 16 -1 (-525 2775)(-725 2775);
WIRE 16 -1 (-525 2875)(-525 2825);
WIRE 16 -1 (-525 2825)(-725 2825);
WIRE 16 -1 (-525 2925)(-525 2875);
WIRE 16 -1 (-525 2875)(-725 2875);
WIRE 16 -1 (-525 2975)(-525 2925);
WIRE 16 -1 (-525 2925)(-725 2925);
WIRE 16 -1 (-525 3025)(-525 2975);
WIRE 16 -1 (-525 2975)(-725 2975);
WIRE 16 -1 (-525 3075)(-525 3025);
WIRE 16 -1 (-525 3025)(-725 3025);
WIRE 16 -1 (-525 3125)(-525 3075);
WIRE 16 -1 (-525 3075)(-725 3075);
WIRE 16 -1 (-525 3175)(-525 3125);
WIRE 16 -1 (-525 3125)(-725 3125);
WIRE 16 -1 (-525 3225)(-525 3175);
WIRE 16 -1 (-525 3175)(-725 3175);
WIRE 16 -1 (-525 3275)(-525 3225);
WIRE 16 -1 (-525 3225)(-725 3225);
WIRE 16 -1 (-525 3325)(-525 3275);
WIRE 16 -1 (-525 3275)(-725 3275);
WIRE 16 -1 (-525 3375)(-525 3325);
WIRE 16 -1 (-525 3325)(-725 3325);
WIRE 16 -1 (-525 3425)(-525 3375);
WIRE 16 -1 (-525 3375)(-725 3375);
WIRE 16 -1 (-525 3475)(-525 3425);
WIRE 16 -1 (-525 3425)(-725 3425);
WIRE 16 -1 (-525 3525)(-525 3475);
WIRE 16 -1 (-525 3475)(-725 3475);
WIRE 16 -1 (-525 3575)(-525 3525);
WIRE 16 -1 (-525 3525)(-725 3525);
WIRE 16 -1 (-525 3625)(-525 3575);
WIRE 16 -1 (-525 3575)(-725 3575);
WIRE 16 -1 (-525 3675)(-525 3625);
WIRE 16 -1 (-525 3625)(-725 3625);
WIRE 16 -1 (-525 3725)(-525 3675);
WIRE 16 -1 (-525 3675)(-725 3675);
WIRE 16 -1 (-525 3775)(-525 3725);
WIRE 16 -1 (-525 3725)(-725 3725);
WIRE 16 -1 (-525 3825)(-525 3775);
WIRE 16 -1 (-525 3775)(-725 3775);
WIRE 16 -1 (-525 3875)(-525 3825);
WIRE 16 -1 (-525 3825)(-725 3825);
WIRE 16 -1 (-525 3925)(-525 3875);
WIRE 16 -1 (-525 3875)(-725 3875);
WIRE 16 -1 (-525 3975)(-525 3925);
WIRE 16 -1 (-525 3925)(-725 3925);
WIRE 16 -1 (-525 4025)(-525 3975);
WIRE 16 -1 (-525 3975)(-725 3975);
WIRE 16 -1 (-525 4075)(-525 4025);
WIRE 16 -1 (-525 4025)(-725 4025);
WIRE 16 -1 (-525 4125)(-525 4075);
WIRE 16 -1 (-525 4075)(-725 4075);
WIRE 16 -1 (-525 4175)(-525 4125);
WIRE 16 -1 (-525 4125)(-725 4125);
WIRE 16 -1 (-525 4225)(-525 4175);
WIRE 16 -1 (-525 4175)(-725 4175);
WIRE 16 -1 (-525 4275)(-525 4225);
WIRE 16 -1 (-525 4225)(-725 4225);
WIRE 16 -1 (-525 4325)(-525 4275);
WIRE 16 -1 (-525 4275)(-725 4275);
WIRE 16 -1 (-525 4375)(-525 4325);
WIRE 16 -1 (-525 4325)(-725 4325);
WIRE 16 -1 (-525 4425)(-525 4375);
WIRE 16 -1 (-525 4375)(-725 4375);
WIRE 16 -1 (-525 4475)(-525 4425);
WIRE 16 -1 (-525 4425)(-725 4425);
WIRE 16 -1 (-525 4525)(-525 4475);
WIRE 16 -1 (-525 4475)(-725 4475);
WIRE 16 -1 (-525 4575)(-525 4525);
WIRE 16 -1 (-525 4525)(-725 4525);
WIRE 16 -1 (-525 4625)(-525 4575);
WIRE 16 -1 (-525 4575)(-725 4575);
WIRE 16 -1 (-525 4675)(-525 4625);
WIRE 16 -1 (-525 4625)(-725 4625);
WIRE 16 -1 (-525 4725)(-525 4675);
WIRE 16 -1 (-525 4675)(-725 4675);
WIRE 16 -1 (-525 4775)(-525 4725);
WIRE 16 -1 (-525 4725)(-725 4725);
WIRE 16 -1 (-525 4825)(-525 4775);
WIRE 16 -1 (-525 4775)(-725 4775);
WIRE 16 -1 (-525 4875)(-525 4825);
WIRE 16 -1 (-525 4825)(-725 4825);
WIRE 16 -1 (-525 4925)(-525 4875);
WIRE 16 -1 (-525 4875)(-725 4875);
WIRE 16 -1 (-525 4975)(-525 4925);
WIRE 16 -1 (-525 4925)(-725 4925);
WIRE 16 -1 (-525 5025)(-525 4975);
WIRE 16 -1 (-525 4975)(-725 4975);
WIRE 16 -1 (-525 5075)(-525 5025);
WIRE 16 -1 (-525 5025)(-725 5025);
WIRE 16 -1 (-525 5125)(-525 5075);
WIRE 16 -1 (-525 5075)(-725 5075);
WIRE 16 -1 (-525 5175)(-525 5125);
WIRE 16 -1 (-525 5125)(-725 5125);
WIRE 16 -1 (-525 5225)(-525 5175);
WIRE 16 -1 (-525 5175)(-725 5175);
WIRE 16 -1 (-525 5275)(-525 5225);
WIRE 16 -1 (-525 5225)(-725 5225);
WIRE 16 -1 (-525 5275)(-725 5275);
WIRE 16 -1 (-1925 2075)(-2125 2075);
WIRE 16 -1 (-2125 2125)(-2125 2075);
WIRE 16 -1 (-2125 2075)(-2125 2025);
WIRE 16 -1 (-1925 2025)(-2125 2025);
WIRE 16 -1 (-2125 2025)(-2125 1925);
WIRE 16 -1 (-1925 2125)(-2125 2125);
WIRE 16 -1 (-2125 2175)(-2125 2125);
WIRE 16 -1 (-1925 2175)(-2125 2175);
WIRE 16 -1 (-2125 2225)(-2125 2175);
WIRE 16 -1 (-1925 2225)(-2125 2225);
WIRE 16 -1 (-2125 2275)(-2125 2225);
WIRE 16 -1 (-1925 2275)(-2125 2275);
WIRE 16 -1 (-2125 2325)(-2125 2275);
WIRE 16 -1 (-1925 2325)(-2125 2325);
WIRE 16 -1 (-2125 2375)(-2125 2325);
WIRE 16 -1 (-1925 2375)(-2125 2375);
WIRE 16 -1 (-2125 2425)(-2125 2375);
WIRE 16 -1 (-1925 2425)(-2125 2425);
WIRE 16 -1 (-2125 2475)(-2125 2425);
WIRE 16 -1 (-1925 2475)(-2125 2475);
WIRE 16 -1 (-2125 2525)(-2125 2475);
WIRE 16 -1 (-1925 2525)(-2125 2525);
WIRE 16 -1 (-2125 2575)(-2125 2525);
WIRE 16 -1 (-1925 2575)(-2125 2575);
WIRE 16 -1 (-2125 2625)(-2125 2575);
WIRE 16 -1 (-1925 2625)(-2125 2625);
WIRE 16 -1 (-2125 2675)(-2125 2625);
WIRE 16 -1 (-1925 2675)(-2125 2675);
WIRE 16 -1 (-2125 2725)(-2125 2675);
WIRE 16 -1 (-1925 2725)(-2125 2725);
WIRE 16 -1 (-2125 2775)(-2125 2725);
WIRE 16 -1 (-1925 2775)(-2125 2775);
WIRE 16 -1 (-2125 2825)(-2125 2775);
WIRE 16 -1 (-1925 2825)(-2125 2825);
WIRE 16 -1 (-2125 2875)(-2125 2825);
WIRE 16 -1 (-1925 2875)(-2125 2875);
WIRE 16 -1 (-2125 2925)(-2125 2875);
WIRE 16 -1 (-1925 2925)(-2125 2925);
WIRE 16 -1 (-2125 2975)(-2125 2925);
WIRE 16 -1 (-1925 2975)(-2125 2975);
WIRE 16 -1 (-2125 3025)(-2125 2975);
WIRE 16 -1 (-1925 3025)(-2125 3025);
WIRE 16 -1 (-2125 3075)(-2125 3025);
WIRE 16 -1 (-1925 3075)(-2125 3075);
WIRE 16 -1 (-2125 3125)(-2125 3075);
WIRE 16 -1 (-1925 3125)(-2125 3125);
WIRE 16 -1 (-2125 3175)(-2125 3125);
WIRE 16 -1 (-1925 3175)(-2125 3175);
WIRE 16 -1 (-2125 3225)(-2125 3175);
WIRE 16 -1 (-1925 3225)(-2125 3225);
WIRE 16 -1 (-2125 3275)(-2125 3225);
WIRE 16 -1 (-1925 3275)(-2125 3275);
WIRE 16 -1 (-2125 3325)(-2125 3275);
WIRE 16 -1 (-1925 3325)(-2125 3325);
WIRE 16 -1 (-2125 3375)(-2125 3325);
WIRE 16 -1 (-1925 3375)(-2125 3375);
WIRE 16 -1 (-2125 3425)(-2125 3375);
WIRE 16 -1 (-1925 3425)(-2125 3425);
WIRE 16 -1 (-2125 3475)(-2125 3425);
WIRE 16 -1 (-1925 3475)(-2125 3475);
WIRE 16 -1 (-2125 3525)(-2125 3475);
WIRE 16 -1 (-1925 3525)(-2125 3525);
WIRE 16 -1 (-2125 3575)(-2125 3525);
WIRE 16 -1 (-1925 3575)(-2125 3575);
WIRE 16 -1 (-2125 3625)(-2125 3575);
WIRE 16 -1 (-1925 3625)(-2125 3625);
WIRE 16 -1 (-2125 3675)(-2125 3625);
WIRE 16 -1 (-1925 3675)(-2125 3675);
WIRE 16 -1 (-2125 3725)(-2125 3675);
WIRE 16 -1 (-1925 3725)(-2125 3725);
WIRE 16 -1 (-2125 3775)(-2125 3725);
WIRE 16 -1 (-1925 3775)(-2125 3775);
WIRE 16 -1 (-2125 3825)(-2125 3775);
WIRE 16 -1 (-1925 3825)(-2125 3825);
WIRE 16 -1 (-2125 3875)(-2125 3825);
WIRE 16 -1 (-1925 3875)(-2125 3875);
WIRE 16 -1 (-2125 3925)(-2125 3875);
WIRE 16 -1 (-1925 3925)(-2125 3925);
WIRE 16 -1 (-2125 3975)(-2125 3925);
WIRE 16 -1 (-1925 3975)(-2125 3975);
WIRE 16 -1 (-2125 4025)(-2125 3975);
WIRE 16 -1 (-1925 4025)(-2125 4025);
WIRE 16 -1 (-2125 4075)(-2125 4025);
WIRE 16 -1 (-2125 4125)(-2125 4075);
WIRE 16 -1 (-1925 4075)(-2125 4075);
WIRE 16 -1 (-1925 4125)(-2125 4125);
WIRE 16 -1 (-2125 4175)(-2125 4125);
WIRE 16 -1 (-1925 4175)(-2125 4175);
WIRE 16 -1 (-2125 4225)(-2125 4175);
WIRE 16 -1 (-1925 4225)(-2125 4225);
WIRE 16 -1 (-2125 4275)(-2125 4225);
WIRE 16 -1 (-1925 4275)(-2125 4275);
WIRE 16 -1 (-2125 4325)(-2125 4275);
WIRE 16 -1 (-1925 4325)(-2125 4325);
WIRE 16 -1 (-2125 4375)(-2125 4325);
WIRE 16 -1 (-1925 4375)(-2125 4375);
WIRE 16 -1 (-2125 4425)(-2125 4375);
WIRE 16 -1 (-1925 4425)(-2125 4425);
WIRE 16 -1 (-2125 4475)(-2125 4425);
WIRE 16 -1 (-1925 4475)(-2125 4475);
WIRE 16 -1 (-2125 4525)(-2125 4475);
WIRE 16 -1 (-1925 4525)(-2125 4525);
WIRE 16 -1 (-2125 4575)(-2125 4525);
WIRE 16 -1 (-1925 4575)(-2125 4575);
WIRE 16 -1 (-2125 4625)(-2125 4575);
WIRE 16 -1 (-1925 4625)(-2125 4625);
WIRE 16 -1 (-2125 4675)(-2125 4625);
WIRE 16 -1 (-1925 4675)(-2125 4675);
WIRE 16 -1 (-2125 4725)(-2125 4675);
WIRE 16 -1 (-1925 4725)(-2125 4725);
WIRE 16 -1 (-2125 4775)(-2125 4725);
WIRE 16 -1 (-1925 4775)(-2125 4775);
WIRE 16 -1 (-2125 4825)(-2125 4775);
WIRE 16 -1 (-1925 4825)(-2125 4825);
WIRE 16 -1 (-2125 4875)(-2125 4825);
WIRE 16 -1 (-1925 4875)(-2125 4875);
WIRE 16 -1 (-2125 4925)(-2125 4875);
WIRE 16 -1 (-1925 4925)(-2125 4925);
WIRE 16 -1 (-2125 4975)(-2125 4925);
WIRE 16 -1 (-1925 4975)(-2125 4975);
WIRE 16 -1 (-2125 5025)(-2125 4975);
WIRE 16 -1 (-1925 5025)(-2125 5025);
WIRE 16 -1 (-2125 5075)(-2125 5025);
WIRE 16 -1 (-1925 5075)(-2125 5075);
WIRE 16 -1 (-2125 5125)(-2125 5075);
WIRE 16 -1 (-1925 5125)(-2125 5125);
WIRE 16 -1 (-2325 750)(-1275 750);
FORCEPROP 2 LAST SIG_NAME PWRGD_CHGL_CPU1_R2
J 0
(-2010 760);
DISPLAY 0.680851 (-2010 760);
WIRE 16 -1 (-6025 5350)(-5825 5350);
WIRE 16 -1 (-7225 3800)(-7425 3800);
WIRE 16 -1 (-7225 3650)(-7425 3650);
WIRE 16 -1 (-7225 3500)(-7425 3500);
WIRE 16 -1 (-7225 4650)(-7425 4650);
WIRE 16 -1 (-7225 4700)(-7425 4700);
WIRE 16 -1 (-7225 4750)(-7425 4750);
WIRE 16 -1 (-7225 4800)(-7425 4800);
WIRE 16 -1 (-7225 5250)(-7425 5250);
WIRE 16 -1 (-7225 4850)(-7425 4850);
WIRE 16 -1 (-7225 5300)(-7425 5300);
WIRE 16 -1 (-7225 4900)(-7425 4900);
WIRE 16 -1 (-7225 5350)(-7425 5350);
WIRE 16 -1 (-7225 4950)(-7425 4950);
WIRE 16 -1 (-7225 3900)(-7425 3900);
WIRE 16 -1 (-7225 3850)(-7425 3850);
WIRE 16 -1 (-7225 3750)(-7425 3750);
WIRE 16 -1 (-7225 3700)(-7425 3700);
WIRE 16 -1 (-7225 3600)(-7425 3600);
WIRE 16 -1 (-7225 3400)(-7425 3400);
WIRE 16 -1 (-7225 3350)(-7425 3350);
WIRE 16 -1 (-7225 3300)(-7425 3300);
WIRE 16 -1 (-7225 3250)(-7425 3250);
WIRE 16 -1 (-7225 4050)(-8025 4050);
FORCEPROP 2 LAST SIG_NAME M_G_CPU1_CLK_DN<0>
J 0
(-8025 4060);
DISPLAY 0.489362 (-8025 4060);
WIRE 16 -1 (-7225 4100)(-8025 4100);
FORCEPROP 2 LAST SIG_NAME M_G_CPU1_CLK_DP<0>
J 0
(-8025 4110);
DISPLAY 0.489362 (-8025 4110);
WIRE 16 -1 (-7225 4350)(-8025 4350);
FORCEPROP 2 LAST SIG_NAME M_G_CPU1_SA_CS_N<0>
J 0
(-8025 4360);
DISPLAY 0.489362 (-8025 4360);
WIRE 16 -1 (-7225 4200)(-8025 4200);
FORCEPROP 2 LAST SIG_NAME M_G_CPU1_SB_CS_N<0>
J 0
(-8025 4210);
DISPLAY 0.489362 (-8025 4210);
WIRE 16 -1 (-7225 4400)(-8025 4400);
FORCEPROP 2 LAST SIG_NAME M_G_CPU1_SA_CS_N<1>
J 0
(-8025 4410);
DISPLAY 0.489362 (-8025 4410);
WIRE 16 -1 (-7225 4250)(-8025 4250);
FORCEPROP 2 LAST SIG_NAME M_G_CPU1_SB_CS_N<1>
J 0
(-8025 4260);
DISPLAY 0.489362 (-8025 4260);
WIRE 16 -1 (-5825 5300)(-6025 5300);
WIRE 16 -1 (-5825 5250)(-6025 5250);
WIRE 16 -1 (-5825 5200)(-6025 5200);
WIRE 16 -1 (-6025 5150)(-5825 5150);
WIRE 16 -1 (-5825 5100)(-6025 5100);
WIRE 16 -1 (-5825 5050)(-6025 5050);
WIRE 16 -1 (-5825 5000)(-6025 5000);
WIRE 16 -1 (-6025 4950)(-5825 4950);
WIRE 16 -1 (-5825 4900)(-6025 4900);
WIRE 16 -1 (-5825 4850)(-6025 4850);
WIRE 16 -1 (-5825 4800)(-6025 4800);
WIRE 16 -1 (-6025 4750)(-5825 4750);
WIRE 16 -1 (-5825 4700)(-6025 4700);
WIRE 16 -1 (-5825 4650)(-6025 4650);
WIRE 16 -1 (-5825 4600)(-6025 4600);
WIRE 16 -1 (-6025 4550)(-5825 4550);
WIRE 16 -1 (-5825 4500)(-6025 4500);
WIRE 16 -1 (-5825 4450)(-6025 4450);
WIRE 16 -1 (-5825 4400)(-6025 4400);
WIRE 16 -1 (-6025 4350)(-5825 4350);
WIRE 16 -1 (-5825 4300)(-6025 4300);
WIRE 16 -1 (-5825 4250)(-6025 4250);
WIRE 16 -1 (-5825 4200)(-6025 4200);
WIRE 16 -1 (-6025 4150)(-5825 4150);
WIRE 16 -1 (-5825 4100)(-6025 4100);
WIRE 16 -1 (-5825 4050)(-6025 4050);
WIRE 16 -1 (-5825 4000)(-6025 4000);
WIRE 16 -1 (-6025 3950)(-5825 3950);
WIRE 16 -1 (-5825 3900)(-6025 3900);
WIRE 16 -1 (-5825 3850)(-6025 3850);
WIRE 16 -1 (-5825 3800)(-6025 3800);
WIRE 16 -1 (-6025 3700)(-5825 3700);
WIRE 16 -1 (-5825 3650)(-6025 3650);
WIRE 16 -1 (-5825 3600)(-6025 3600);
WIRE 16 -1 (-5825 3550)(-6025 3550);
WIRE 16 -1 (-6025 3500)(-5825 3500);
WIRE 16 -1 (-5825 3450)(-6025 3450);
WIRE 16 -1 (-5825 3400)(-6025 3400);
WIRE 16 -1 (-5825 3350)(-6025 3350);
WIRE 16 -1 (-6025 3300)(-5825 3300);
WIRE 16 -1 (-5825 3250)(-6025 3250);
WIRE 16 -1 (-5825 3200)(-6025 3200);
WIRE 16 -1 (-5825 3150)(-6025 3150);
WIRE 16 -1 (-6025 3100)(-5825 3100);
WIRE 16 -1 (-5825 3050)(-6025 3050);
WIRE 16 -1 (-5825 3000)(-6025 3000);
WIRE 16 -1 (-5825 2950)(-6025 2950);
WIRE 16 -1 (-5825 2800)(-6025 2800);
WIRE 16 -1 (-5825 2750)(-6025 2750);
WIRE 16 -1 (-6025 2700)(-5825 2700);
WIRE 16 -1 (-5825 2650)(-6025 2650);
WIRE 16 -1 (-5825 2600)(-6025 2600);
WIRE 16 -1 (-5825 2550)(-6025 2550);
WIRE 16 -1 (-6025 2500)(-5825 2500);
WIRE 16 -1 (-5825 2450)(-6025 2450);
WIRE 16 -1 (-5825 2400)(-6025 2400);
WIRE 16 -1 (-5825 2350)(-6025 2350);
WIRE 16 -1 (-6025 2300)(-5825 2300);
WIRE 16 -1 (-5825 2250)(-6025 2250);
WIRE 16 -1 (-5825 2200)(-6025 2200);
WIRE 16 -1 (-5825 2150)(-6025 2150);
WIRE 16 -1 (-7225 1950)(-8025 1950);
FORCEPROP 2 LAST SIG_NAME M_G_CPU1_SA_RSP<0>
J 0
(-8025 1960);
DISPLAY 0.489362 (-8025 1960);
WIRE 16 -1 (-7225 1900)(-8025 1900);
FORCEPROP 2 LAST SIG_NAME M_G_CPU1_SB_RSP<0>
J 0
(-8025 1910);
DISPLAY 0.489362 (-8025 1910);
WIRE 16 -1 (-7225 4550)(-8025 4550);
FORCEPROP 2 LAST SIG_NAME M_G_CPU1_SA_PAR
J 0
(-8025 4560);
DISPLAY 0.489362 (-8025 4560);
WIRE 16 -1 (-7225 4500)(-8025 4500);
FORCEPROP 2 LAST SIG_NAME M_G_CPU1_SB_PAR
J 0
(-8025 4510);
DISPLAY 0.489362 (-8025 4510);
WIRE 16 -1 (-3500 4175)(-3100 4175);
WIRE 16 -1 (-3300 4125)(-3500 4125);
WIRE 16 -1 (-3300 3275)(-3500 3275);
WIRE 16 -1 (-3500 3225)(-3100 3225);
WIRE 16 -1 (-3300 3175)(-3500 3175);
WIRE 16 -1 (-3500 3475)(-3100 3475);
WIRE 16 -1 (-3300 3525)(-3500 3525);
WIRE 16 -1 (-3500 2425)(-3100 2425);
WIRE 16 -1 (-3300 2475)(-3500 2475);
WIRE 16 -1 (-3500 3575)(-3100 3575);
WIRE 16 -1 (-3500 3625)(-3300 3625);
WIRE 16 -1 (-3500 2525)(-3100 2525);
WIRE 16 -1 (-3500 2575)(-3300 2575);
WIRE 16 -1 (-3500 3675)(-3100 3675);
WIRE 16 -1 (-3300 3725)(-3500 3725);
WIRE 16 -1 (-3500 2625)(-3100 2625);
WIRE 16 -1 (-3300 2675)(-3500 2675);
WIRE 16 -1 (-3500 3775)(-3100 3775);
WIRE 16 -1 (-3300 3825)(-3500 3825);
WIRE 16 -1 (-3500 2725)(-3100 2725);
WIRE 16 -1 (-3300 2775)(-3500 2775);
WIRE 16 -1 (-3500 3875)(-3100 3875);
WIRE 16 -1 (-3300 3925)(-3500 3925);
WIRE 16 -1 (-3500 2825)(-3100 2825);
WIRE 16 -1 (-3300 2875)(-3500 2875);
WIRE 16 -1 (-3500 3975)(-3100 3975);
WIRE 16 -1 (-3500 4025)(-3300 4025);
WIRE 16 -1 (-3500 2925)(-3100 2925);
WIRE 16 -1 (-3500 2975)(-3300 2975);
WIRE 16 -1 (-3500 4075)(-3100 4075);
WIRE 16 -1 (-3500 3025)(-3100 3025);
WIRE 16 -1 (-3300 3075)(-3500 3075);
WIRE 16 -1 (-3300 4225)(-3500 4225);
WIRE 16 -1 (-3500 3125)(-3100 3125);
WIRE 16 -1 (-3500 4275)(-3100 4275);
WIRE 16 -1 (-3300 4325)(-3500 4325);
WIRE 16 -1 (-3500 4375)(-3100 4375);
WIRE 16 -1 (-3500 4425)(-3300 4425);
WIRE 16 -1 (-3500 3325)(-3100 3325);
WIRE 16 -1 (-3500 3375)(-3300 3375);
WIRE 16 -1 (-7225 5050)(-7425 5050);
WIRE 16 -1 (-7225 5100)(-7425 5100);
WIRE 16 -1 (-7225 5150)(-7425 5150);
WIRE 16 -1 (-7225 5200)(-7425 5200);
WIRE 16 -1 (-7225 3950)(-7425 3950);
WIRE 16 -1 (-8900 2100)(-8525 2100);
FORCEPROP 2 LAST SIG_NAME PWRGD_CHGL_CPU1
J 0
(-8885 2110);
DISPLAY 0.489362 (-8885 2110);
WIRE 16 -1 (-8525 2150)(-8525 2100);
WIRE 16 -1 (-8525 2100)(-8500 2100);
WIRE 16 -1 (-8025 2800)(-8000 2800);
WIRE 16 -1 (-8025 2700)(-8025 2800);
WIRE 16 -1 (-8025 2700)(-8550 2700);
FORCEPROP 2 LAST SIG_NAME I3C_SPD_DDRGL_CPU1_SDA
J 0
(-8560 2710);
DISPLAY 0.489362 (-8560 2710);
WIRE 16 -1 (-7625 2575)(-8075 2575);
FORCEPROP 2 LAST SIG_NAME I3C_SPD_DDRGL_CPU1_SCL
J 0
(-8110 2585);
DISPLAY 0.489362 (-8110 2585);
DOT 1 (-3600 750);
DOT 1 (-2625 750);
DOT 1 (-2825 5650);
DOT 1 (-2125 5075);
DOT 1 (-525 5225);
DOT 1 (-525 5175);
DOT 1 (-525 5075);
DOT 1 (-525 5125);
DOT 1 (-525 5025);
DOT 1 (-525 4975);
DOT 1 (-525 4925);
DOT 1 (-525 4875);
DOT 1 (-525 4825);
DOT 1 (-525 4775);
DOT 1 (-525 4725);
DOT 1 (-525 4675);
DOT 1 (-525 4625);
DOT 1 (-525 4575);
DOT 1 (-525 4525);
DOT 1 (-525 4375);
DOT 1 (-525 4425);
DOT 1 (-525 4475);
DOT 1 (-525 4325);
DOT 1 (-525 4275);
DOT 1 (-525 4225);
DOT 1 (-525 4125);
DOT 1 (-525 4175);
DOT 1 (-525 4075);
DOT 1 (-525 4025);
DOT 1 (-525 3975);
DOT 1 (-525 3875);
DOT 1 (-525 3925);
DOT 1 (-2125 5275);
DOT 1 (-2125 5225);
DOT 1 (-2125 5025);
DOT 1 (-2125 4975);
DOT 1 (-2125 4925);
DOT 1 (-2125 4875);
DOT 1 (-2125 4825);
DOT 1 (-2125 4775);
DOT 1 (-2125 4675);
DOT 1 (-2125 4725);
DOT 1 (-2125 4625);
DOT 1 (-2125 4525);
DOT 1 (-2125 4575);
DOT 1 (-2125 4425);
DOT 1 (-2125 4475);
DOT 1 (-2125 4375);
DOT 1 (-2125 4325);
DOT 1 (-2125 4275);
DOT 1 (-2125 4225);
DOT 1 (-2125 4125);
DOT 1 (-2125 4175);
DOT 1 (-2125 4075);
DOT 1 (-2125 4025);
DOT 1 (-2125 3975);
DOT 1 (-2125 3925);
DOT 1 (-2125 3875);
DOT 1 (-525 3825);
DOT 1 (-525 3775);
DOT 1 (-525 3725);
DOT 1 (-525 3675);
DOT 1 (-525 3625);
DOT 1 (-525 3575);
DOT 1 (-525 3525);
DOT 1 (-525 3475);
DOT 1 (-525 3425);
DOT 1 (-525 3375);
DOT 1 (-525 3275);
DOT 1 (-525 3225);
DOT 1 (-525 3325);
DOT 1 (-525 3175);
DOT 1 (-525 3125);
DOT 1 (-525 3025);
DOT 1 (-525 3075);
DOT 1 (-525 2975);
DOT 1 (-525 2925);
DOT 1 (-525 2875);
DOT 1 (-525 2825);
DOT 1 (-525 2775);
DOT 1 (-525 2725);
DOT 1 (-525 2625);
DOT 1 (-525 2675);
DOT 1 (-525 2575);
DOT 1 (-525 2525);
DOT 1 (-525 2475);
DOT 1 (-525 2425);
DOT 1 (-525 2375);
DOT 1 (-525 2325);
DOT 1 (-525 2275);
DOT 1 (-525 2225);
DOT 1 (-525 2125);
DOT 1 (-525 2175);
DOT 1 (-525 2025);
DOT 1 (-525 1975);
DOT 1 (-525 1925);
DOT 1 (-2125 3825);
DOT 1 (-2125 3775);
DOT 1 (-2125 3725);
DOT 1 (-2125 3675);
DOT 1 (-2125 3625);
DOT 1 (-2125 3575);
DOT 1 (-2125 3525);
DOT 1 (-2125 3475);
DOT 1 (-2125 3425);
DOT 1 (-2125 3375);
DOT 1 (-2125 3325);
DOT 1 (-2125 3275);
DOT 1 (-2125 3225);
DOT 1 (-2125 3175);
DOT 1 (-2125 3125);
DOT 1 (-2125 3075);
DOT 1 (-2125 3025);
DOT 1 (-2125 2975);
DOT 1 (-2125 2875);
DOT 1 (-2125 2925);
DOT 1 (-2125 2825);
DOT 1 (-2125 2775);
DOT 1 (-2125 2725);
DOT 1 (-2125 2625);
DOT 1 (-2125 2675);
DOT 1 (-2125 2575);
DOT 1 (-2125 2525);
DOT 1 (-2125 2475);
DOT 1 (-2125 2425);
DOT 1 (-2125 2325);
DOT 1 (-2125 2375);
DOT 1 (-2125 2275);
DOT 1 (-2125 2225);
DOT 1 (-2125 2175);
DOT 1 (-2125 2075);
DOT 1 (-2125 2125);
DOT 1 (-2125 2025);
DOT 1 (-8575 3325);
DOT 1 (-8275 2100);
DOT 1 (-8525 2100);
DOT 1 (-2825 6075);
DOT 1 (-2250 6075);
QUIT
